FILE_TYPE = MACRO_DRAWING;
SET COLOR_WIRE YELLOW;
SET COLOR_PROP MONO;
SET COLOR_DOT WHITE;
SET COLOR_ARC YELLOW;
SET COLOR_BODY GREEN;
SET COLOR_NOTE MONO;
SET PROP_DISPLAY VALUE;
SET PAGE_NUMBER P24;
FORCEADD OFFPAGE..5
(-6375 500);
FORCEPROP 2 LAST $XR1 46 
J 0
(-6719 500);
DISPLAY 0.638298 (-6719 500);
PAINT MONO (-6719 500);
FORCEPROP 2 LAST $XR0 45 
J 0
(-6629 500);
DISPLAY 0.638298 (-6629 500);
PAINT MONO (-6629 500);
FORCEPROP 1 LAST COMMENT_BODY TRUE
J 0
(-6275 425);
DISPLAY 1.170213 (-6275 425);
PAINT GREEN (-6275 425);
DISPLAY INVISIBLE (-6275 425);
FORCEPROP 1 LAST OFFPAGE TRUE
J 0
(-6050 375);
DISPLAY 1.170213 (-6050 375);
PAINT GREEN (-6050 375);
DISPLAY INVISIBLE (-6050 375);
FORCEPROP 2 LAST CDS_LIB mstr_standard
J 0
(-6375 500);
PAINT MONO (-6375 500);
DISPLAY INVISIBLE (-6375 500);
FORCEPROP 2 LAST PATH I1
J 0
(-6325 575);
DISPLAY 1.021277 (-6325 575);
PAINT ORANGE (-6325 575);
DISPLAY INVISIBLE (-6325 575);
FORCEADD TAP..6
(-5525 750);
FORCEPROP 3 LASTPIN (-5475 750) SIG_NAME M_B_CLK_DN<3>
J 0
(-5465 760);
DISPLAY 0.659574 (-5465 760);
PAINT MONO (-5465 760);
DISPLAY INVISIBLE (-5465 760);
FORCEPROP 1 LASTPIN (-5475 750) BN 3
J 0
(-5527 758);
DISPLAY 0.617021 (-5527 758);
PAINT PINK (-5527 758);
FORCEPROP 1 LAST HDL_TAP TRUE
J 0
(-5200 625);
DISPLAY 1.595745 (-5200 625);
PAINT GREEN (-5200 625);
DISPLAY INVISIBLE (-5200 625);
FORCEPROP 1 LAST BODY_TYPE PLUMBING
J 0
(-5525 700);
DISPLAY 1.595745 (-5525 700);
PAINT GREEN (-5525 700);
DISPLAY INVISIBLE (-5525 700);
FORCEPROP 2 LAST CDS_LIB mstr_standard
J 0
(-5525 750);
PAINT MONO (-5525 750);
DISPLAY INVISIBLE (-5525 750);
FORCEPROP 1 LAST PATH I10
J 0
(-5527 750);
DISPLAY 0.872340 (-5527 750);
PAINT GREEN (-5527 750);
DISPLAY INVISIBLE (-5527 750);
FORCEADD TAP..6
R 2
(-2800 1550);
FORCEPROP 3 LASTPIN (-2850 1550) SIG_NAME M_B_ODT<3>
J 0
(-2840 1560);
DISPLAY 0.659574 (-2840 1560);
PAINT MONO (-2840 1560);
DISPLAY INVISIBLE (-2840 1560);
FORCEPROP 1 LASTPIN (-2850 1550) BN 3
J 2
(-2798 1558);
DISPLAY 0.617021 (-2798 1558);
PAINT PINK (-2798 1558);
FORCEPROP 1 LAST HDL_TAP TRUE
J 2
(-3125 1425);
DISPLAY 1.595745 (-3125 1425);
PAINT GREEN (-3125 1425);
DISPLAY INVISIBLE (-3125 1425);
FORCEPROP 1 LAST BODY_TYPE PLUMBING
J 2
(-2800 1500);
DISPLAY 1.595745 (-2800 1500);
PAINT GREEN (-2800 1500);
DISPLAY INVISIBLE (-2800 1500);
FORCEPROP 2 LAST CDS_LIB mstr_standard
J 0
(-2800 1550);
PAINT MONO (-2800 1550);
DISPLAY INVISIBLE (-2800 1550);
FORCEPROP 1 LAST PATH I100
J 2
(-2798 1550);
DISPLAY 0.872340 (-2798 1550);
PAINT GREEN (-2798 1550);
DISPLAY INVISIBLE (-2798 1550);
FORCEADD TAP..6
R 2
(-2800 1450);
FORCEPROP 3 LASTPIN (-2850 1450) SIG_NAME M_B_ODT<1>
J 0
(-2840 1460);
DISPLAY 0.659574 (-2840 1460);
PAINT MONO (-2840 1460);
DISPLAY INVISIBLE (-2840 1460);
FORCEPROP 1 LASTPIN (-2850 1450) BN 1
J 2
(-2798 1458);
DISPLAY 0.617021 (-2798 1458);
PAINT PINK (-2798 1458);
FORCEPROP 1 LAST HDL_TAP TRUE
J 2
(-3125 1325);
DISPLAY 1.595745 (-3125 1325);
PAINT GREEN (-3125 1325);
DISPLAY INVISIBLE (-3125 1325);
FORCEPROP 1 LAST BODY_TYPE PLUMBING
J 2
(-2800 1400);
DISPLAY 1.595745 (-2800 1400);
PAINT GREEN (-2800 1400);
DISPLAY INVISIBLE (-2800 1400);
FORCEPROP 2 LAST CDS_LIB mstr_standard
J 0
(-2800 1450);
PAINT MONO (-2800 1450);
DISPLAY INVISIBLE (-2800 1450);
FORCEPROP 1 LAST PATH I101
J 2
(-2798 1450);
DISPLAY 0.872340 (-2798 1450);
PAINT GREEN (-2798 1450);
DISPLAY INVISIBLE (-2798 1450);
FORCEADD TAP..6
R 2
(-2800 1650);
FORCEPROP 3 LASTPIN (-2850 1650) SIG_NAME M_B_CKE<0>
J 0
(-2840 1660);
DISPLAY 0.659574 (-2840 1660);
PAINT MONO (-2840 1660);
DISPLAY INVISIBLE (-2840 1660);
FORCEPROP 1 LASTPIN (-2850 1650) BN 0
J 2
(-2798 1658);
DISPLAY 0.617021 (-2798 1658);
PAINT PINK (-2798 1658);
FORCEPROP 1 LAST HDL_TAP TRUE
J 2
(-3125 1525);
DISPLAY 1.595745 (-3125 1525);
PAINT GREEN (-3125 1525);
DISPLAY INVISIBLE (-3125 1525);
FORCEPROP 1 LAST BODY_TYPE PLUMBING
J 2
(-2800 1600);
DISPLAY 1.595745 (-2800 1600);
PAINT GREEN (-2800 1600);
DISPLAY INVISIBLE (-2800 1600);
FORCEPROP 2 LAST CDS_LIB mstr_standard
J 0
(-2800 1650);
PAINT MONO (-2800 1650);
DISPLAY INVISIBLE (-2800 1650);
FORCEPROP 1 LAST PATH I102
J 2
(-2798 1650);
DISPLAY 0.872340 (-2798 1650);
PAINT GREEN (-2798 1650);
DISPLAY INVISIBLE (-2798 1650);
FORCEADD TAP..6
R 2
(-2800 1500);
FORCEPROP 3 LASTPIN (-2850 1500) SIG_NAME M_B_ODT<2>
J 0
(-2840 1510);
DISPLAY 0.659574 (-2840 1510);
PAINT MONO (-2840 1510);
DISPLAY INVISIBLE (-2840 1510);
FORCEPROP 1 LASTPIN (-2850 1500) BN 2
J 2
(-2798 1508);
DISPLAY 0.617021 (-2798 1508);
PAINT PINK (-2798 1508);
FORCEPROP 1 LAST HDL_TAP TRUE
J 2
(-3125 1375);
DISPLAY 1.595745 (-3125 1375);
PAINT GREEN (-3125 1375);
DISPLAY INVISIBLE (-3125 1375);
FORCEPROP 1 LAST BODY_TYPE PLUMBING
J 2
(-2800 1450);
DISPLAY 1.595745 (-2800 1450);
PAINT GREEN (-2800 1450);
DISPLAY INVISIBLE (-2800 1450);
FORCEPROP 2 LAST CDS_LIB mstr_standard
J 0
(-2800 1500);
PAINT MONO (-2800 1500);
DISPLAY INVISIBLE (-2800 1500);
FORCEPROP 1 LAST PATH I103
J 2
(-2798 1500);
DISPLAY 0.872340 (-2798 1500);
PAINT GREEN (-2798 1500);
DISPLAY INVISIBLE (-2798 1500);
FORCEADD TAP..6
R 2
(-2800 1750);
FORCEPROP 3 LASTPIN (-2850 1750) SIG_NAME M_B_CKE<2>
J 0
(-2840 1760);
DISPLAY 0.659574 (-2840 1760);
PAINT MONO (-2840 1760);
DISPLAY INVISIBLE (-2840 1760);
FORCEPROP 1 LASTPIN (-2850 1750) BN 2
J 2
(-2798 1758);
DISPLAY 0.617021 (-2798 1758);
PAINT PINK (-2798 1758);
FORCEPROP 1 LAST HDL_TAP TRUE
J 2
(-3125 1625);
DISPLAY 1.595745 (-3125 1625);
PAINT GREEN (-3125 1625);
DISPLAY INVISIBLE (-3125 1625);
FORCEPROP 1 LAST BODY_TYPE PLUMBING
J 2
(-2800 1700);
DISPLAY 1.595745 (-2800 1700);
PAINT GREEN (-2800 1700);
DISPLAY INVISIBLE (-2800 1700);
FORCEPROP 2 LAST CDS_LIB mstr_standard
J 0
(-2800 1750);
PAINT MONO (-2800 1750);
DISPLAY INVISIBLE (-2800 1750);
FORCEPROP 1 LAST PATH I104
J 2
(-2798 1750);
DISPLAY 0.872340 (-2798 1750);
PAINT GREEN (-2798 1750);
DISPLAY INVISIBLE (-2798 1750);
FORCEADD TAP..6
R 2
(-2800 1700);
FORCEPROP 3 LASTPIN (-2850 1700) SIG_NAME M_B_CKE<1>
J 0
(-2840 1710);
DISPLAY 0.659574 (-2840 1710);
PAINT MONO (-2840 1710);
DISPLAY INVISIBLE (-2840 1710);
FORCEPROP 1 LASTPIN (-2850 1700) BN 1
J 2
(-2798 1708);
DISPLAY 0.617021 (-2798 1708);
PAINT PINK (-2798 1708);
FORCEPROP 1 LAST HDL_TAP TRUE
J 2
(-3125 1575);
DISPLAY 1.595745 (-3125 1575);
PAINT GREEN (-3125 1575);
DISPLAY INVISIBLE (-3125 1575);
FORCEPROP 1 LAST BODY_TYPE PLUMBING
J 2
(-2800 1650);
DISPLAY 1.595745 (-2800 1650);
PAINT GREEN (-2800 1650);
DISPLAY INVISIBLE (-2800 1650);
FORCEPROP 2 LAST CDS_LIB mstr_standard
J 0
(-2800 1700);
PAINT MONO (-2800 1700);
DISPLAY INVISIBLE (-2800 1700);
FORCEPROP 1 LAST PATH I105
J 2
(-2798 1700);
DISPLAY 0.872340 (-2798 1700);
PAINT GREEN (-2798 1700);
DISPLAY INVISIBLE (-2798 1700);
FORCEADD TAP..6
R 2
(-2800 1900);
FORCEPROP 3 LASTPIN (-2850 1900) SIG_NAME M_B_MA<0>
J 0
(-2840 1910);
DISPLAY 0.659574 (-2840 1910);
PAINT MONO (-2840 1910);
DISPLAY INVISIBLE (-2840 1910);
FORCEPROP 1 LASTPIN (-2850 1900) BN 0
J 2
(-2798 1908);
DISPLAY 0.617021 (-2798 1908);
PAINT PINK (-2798 1908);
FORCEPROP 1 LAST HDL_TAP TRUE
J 2
(-3125 1775);
DISPLAY 1.595745 (-3125 1775);
PAINT GREEN (-3125 1775);
DISPLAY INVISIBLE (-3125 1775);
FORCEPROP 1 LAST BODY_TYPE PLUMBING
J 2
(-2800 1850);
DISPLAY 1.595745 (-2800 1850);
PAINT GREEN (-2800 1850);
DISPLAY INVISIBLE (-2800 1850);
FORCEPROP 2 LAST CDS_LIB mstr_standard
J 0
(-2800 1900);
PAINT MONO (-2800 1900);
DISPLAY INVISIBLE (-2800 1900);
FORCEPROP 1 LAST PATH I106
J 2
(-2798 1900);
DISPLAY 0.872340 (-2798 1900);
PAINT GREEN (-2798 1900);
DISPLAY INVISIBLE (-2798 1900);
FORCEADD TAP..6
R 2
(-2800 1800);
FORCEPROP 3 LASTPIN (-2850 1800) SIG_NAME M_B_CKE<3>
J 0
(-2840 1810);
DISPLAY 0.659574 (-2840 1810);
PAINT MONO (-2840 1810);
DISPLAY INVISIBLE (-2840 1810);
FORCEPROP 1 LASTPIN (-2850 1800) BN 3
J 2
(-2798 1808);
DISPLAY 0.617021 (-2798 1808);
PAINT PINK (-2798 1808);
FORCEPROP 1 LAST HDL_TAP TRUE
J 2
(-3125 1675);
DISPLAY 1.595745 (-3125 1675);
PAINT GREEN (-3125 1675);
DISPLAY INVISIBLE (-3125 1675);
FORCEPROP 1 LAST BODY_TYPE PLUMBING
J 2
(-2800 1750);
DISPLAY 1.595745 (-2800 1750);
PAINT GREEN (-2800 1750);
DISPLAY INVISIBLE (-2800 1750);
FORCEPROP 2 LAST CDS_LIB mstr_standard
J 0
(-2800 1800);
PAINT MONO (-2800 1800);
DISPLAY INVISIBLE (-2800 1800);
FORCEPROP 1 LAST PATH I107
J 2
(-2798 1800);
DISPLAY 0.872340 (-2798 1800);
PAINT GREEN (-2798 1800);
DISPLAY INVISIBLE (-2798 1800);
FORCEADD TAP..6
R 2
(-2800 2100);
FORCEPROP 3 LASTPIN (-2850 2100) SIG_NAME M_B_MA<4>
J 0
(-2840 2110);
DISPLAY 0.659574 (-2840 2110);
PAINT MONO (-2840 2110);
DISPLAY INVISIBLE (-2840 2110);
FORCEPROP 1 LASTPIN (-2850 2100) BN 4
J 2
(-2798 2108);
DISPLAY 0.617021 (-2798 2108);
PAINT PINK (-2798 2108);
FORCEPROP 1 LAST HDL_TAP TRUE
J 2
(-3125 1975);
DISPLAY 1.595745 (-3125 1975);
PAINT GREEN (-3125 1975);
DISPLAY INVISIBLE (-3125 1975);
FORCEPROP 1 LAST BODY_TYPE PLUMBING
J 2
(-2800 2050);
DISPLAY 1.595745 (-2800 2050);
PAINT GREEN (-2800 2050);
DISPLAY INVISIBLE (-2800 2050);
FORCEPROP 2 LAST CDS_LIB mstr_standard
J 0
(-2800 2100);
PAINT MONO (-2800 2100);
DISPLAY INVISIBLE (-2800 2100);
FORCEPROP 1 LAST PATH I108
J 2
(-2798 2100);
DISPLAY 0.872340 (-2798 2100);
PAINT GREEN (-2798 2100);
DISPLAY INVISIBLE (-2798 2100);
FORCEADD TAP..6
R 2
(-2800 2150);
FORCEPROP 3 LASTPIN (-2850 2150) SIG_NAME M_B_MA<5>
J 0
(-2840 2160);
DISPLAY 0.659574 (-2840 2160);
PAINT MONO (-2840 2160);
DISPLAY INVISIBLE (-2840 2160);
FORCEPROP 1 LASTPIN (-2850 2150) BN 5
J 2
(-2798 2158);
DISPLAY 0.617021 (-2798 2158);
PAINT PINK (-2798 2158);
FORCEPROP 1 LAST HDL_TAP TRUE
J 2
(-3125 2025);
DISPLAY 1.595745 (-3125 2025);
PAINT GREEN (-3125 2025);
DISPLAY INVISIBLE (-3125 2025);
FORCEPROP 1 LAST BODY_TYPE PLUMBING
J 2
(-2800 2100);
DISPLAY 1.595745 (-2800 2100);
PAINT GREEN (-2800 2100);
DISPLAY INVISIBLE (-2800 2100);
FORCEPROP 2 LAST CDS_LIB mstr_standard
J 0
(-2800 2150);
PAINT MONO (-2800 2150);
DISPLAY INVISIBLE (-2800 2150);
FORCEPROP 1 LAST PATH I109
J 2
(-2798 2150);
DISPLAY 0.872340 (-2798 2150);
PAINT GREEN (-2798 2150);
DISPLAY INVISIBLE (-2798 2150);
FORCEADD TAP..6
(-5525 900);
FORCEPROP 3 LASTPIN (-5475 900) SIG_NAME M_B_CLK_DP<2>
J 0
(-5465 910);
DISPLAY 0.659574 (-5465 910);
PAINT MONO (-5465 910);
DISPLAY INVISIBLE (-5465 910);
FORCEPROP 1 LASTPIN (-5475 900) BN 2
J 0
(-5527 908);
DISPLAY 0.617021 (-5527 908);
PAINT PINK (-5527 908);
FORCEPROP 1 LAST HDL_TAP TRUE
J 0
(-5200 775);
DISPLAY 1.595745 (-5200 775);
PAINT GREEN (-5200 775);
DISPLAY INVISIBLE (-5200 775);
FORCEPROP 1 LAST BODY_TYPE PLUMBING
J 0
(-5525 850);
DISPLAY 1.595745 (-5525 850);
PAINT GREEN (-5525 850);
DISPLAY INVISIBLE (-5525 850);
FORCEPROP 2 LAST CDS_LIB mstr_standard
J 0
(-5525 900);
PAINT MONO (-5525 900);
DISPLAY INVISIBLE (-5525 900);
FORCEPROP 1 LAST PATH I11
J 0
(-5527 900);
DISPLAY 0.872340 (-5527 900);
PAINT GREEN (-5527 900);
DISPLAY INVISIBLE (-5527 900);
FORCEADD TAP..6
R 2
(-2800 2000);
FORCEPROP 3 LASTPIN (-2850 2000) SIG_NAME M_B_MA<2>
J 0
(-2840 2010);
DISPLAY 0.659574 (-2840 2010);
PAINT MONO (-2840 2010);
DISPLAY INVISIBLE (-2840 2010);
FORCEPROP 1 LASTPIN (-2850 2000) BN 2
J 2
(-2798 2008);
DISPLAY 0.617021 (-2798 2008);
PAINT PINK (-2798 2008);
FORCEPROP 1 LAST HDL_TAP TRUE
J 2
(-3125 1875);
DISPLAY 1.595745 (-3125 1875);
PAINT GREEN (-3125 1875);
DISPLAY INVISIBLE (-3125 1875);
FORCEPROP 1 LAST BODY_TYPE PLUMBING
J 2
(-2800 1950);
DISPLAY 1.595745 (-2800 1950);
PAINT GREEN (-2800 1950);
DISPLAY INVISIBLE (-2800 1950);
FORCEPROP 2 LAST CDS_LIB mstr_standard
J 0
(-2800 2000);
PAINT MONO (-2800 2000);
DISPLAY INVISIBLE (-2800 2000);
FORCEPROP 1 LAST PATH I110
J 2
(-2798 2000);
DISPLAY 0.872340 (-2798 2000);
PAINT GREEN (-2798 2000);
DISPLAY INVISIBLE (-2798 2000);
FORCEADD TAP..6
R 2
(-2800 2050);
FORCEPROP 3 LASTPIN (-2850 2050) SIG_NAME M_B_MA<3>
J 0
(-2840 2060);
DISPLAY 0.659574 (-2840 2060);
PAINT MONO (-2840 2060);
DISPLAY INVISIBLE (-2840 2060);
FORCEPROP 1 LASTPIN (-2850 2050) BN 3
J 2
(-2798 2058);
DISPLAY 0.617021 (-2798 2058);
PAINT PINK (-2798 2058);
FORCEPROP 1 LAST HDL_TAP TRUE
J 2
(-3125 1925);
DISPLAY 1.595745 (-3125 1925);
PAINT GREEN (-3125 1925);
DISPLAY INVISIBLE (-3125 1925);
FORCEPROP 1 LAST BODY_TYPE PLUMBING
J 2
(-2800 2000);
DISPLAY 1.595745 (-2800 2000);
PAINT GREEN (-2800 2000);
DISPLAY INVISIBLE (-2800 2000);
FORCEPROP 2 LAST CDS_LIB mstr_standard
J 0
(-2800 2050);
PAINT MONO (-2800 2050);
DISPLAY INVISIBLE (-2800 2050);
FORCEPROP 1 LAST PATH I111
J 2
(-2798 2050);
DISPLAY 0.872340 (-2798 2050);
PAINT GREEN (-2798 2050);
DISPLAY INVISIBLE (-2798 2050);
FORCEADD TAP..6
R 2
(-2800 1950);
FORCEPROP 3 LASTPIN (-2850 1950) SIG_NAME M_B_MA<1>
J 0
(-2840 1960);
DISPLAY 0.659574 (-2840 1960);
PAINT MONO (-2840 1960);
DISPLAY INVISIBLE (-2840 1960);
FORCEPROP 1 LASTPIN (-2850 1950) BN 1
J 2
(-2798 1958);
DISPLAY 0.617021 (-2798 1958);
PAINT PINK (-2798 1958);
FORCEPROP 1 LAST HDL_TAP TRUE
J 2
(-3125 1825);
DISPLAY 1.595745 (-3125 1825);
PAINT GREEN (-3125 1825);
DISPLAY INVISIBLE (-3125 1825);
FORCEPROP 1 LAST BODY_TYPE PLUMBING
J 2
(-2800 1900);
DISPLAY 1.595745 (-2800 1900);
PAINT GREEN (-2800 1900);
DISPLAY INVISIBLE (-2800 1900);
FORCEPROP 2 LAST CDS_LIB mstr_standard
J 0
(-2800 1950);
PAINT MONO (-2800 1950);
DISPLAY INVISIBLE (-2800 1950);
FORCEPROP 1 LAST PATH I112
J 2
(-2798 1950);
DISPLAY 0.872340 (-2798 1950);
PAINT GREEN (-2798 1950);
DISPLAY INVISIBLE (-2798 1950);
FORCEADD TAP..6
R 2
(-2800 2400);
FORCEPROP 3 LASTPIN (-2850 2400) SIG_NAME M_B_MA<10>
J 0
(-2840 2410);
DISPLAY 0.659574 (-2840 2410);
PAINT MONO (-2840 2410);
DISPLAY INVISIBLE (-2840 2410);
FORCEPROP 1 LASTPIN (-2850 2400) BN 10
J 2
(-2798 2408);
DISPLAY 0.617021 (-2798 2408);
PAINT PINK (-2798 2408);
FORCEPROP 1 LAST HDL_TAP TRUE
J 2
(-3125 2275);
DISPLAY 1.595745 (-3125 2275);
PAINT GREEN (-3125 2275);
DISPLAY INVISIBLE (-3125 2275);
FORCEPROP 1 LAST BODY_TYPE PLUMBING
J 2
(-2800 2350);
DISPLAY 1.595745 (-2800 2350);
PAINT GREEN (-2800 2350);
DISPLAY INVISIBLE (-2800 2350);
FORCEPROP 2 LAST CDS_LIB mstr_standard
J 0
(-2800 2400);
PAINT MONO (-2800 2400);
DISPLAY INVISIBLE (-2800 2400);
FORCEPROP 1 LAST PATH I113
J 2
(-2798 2400);
DISPLAY 0.872340 (-2798 2400);
PAINT GREEN (-2798 2400);
DISPLAY INVISIBLE (-2798 2400);
FORCEADD TAP..6
R 2
(-2800 2350);
FORCEPROP 3 LASTPIN (-2850 2350) SIG_NAME M_B_MA<9>
J 0
(-2840 2360);
DISPLAY 0.659574 (-2840 2360);
PAINT MONO (-2840 2360);
DISPLAY INVISIBLE (-2840 2360);
FORCEPROP 1 LASTPIN (-2850 2350) BN 9
J 2
(-2798 2358);
DISPLAY 0.617021 (-2798 2358);
PAINT PINK (-2798 2358);
FORCEPROP 1 LAST HDL_TAP TRUE
J 2
(-3125 2225);
DISPLAY 1.595745 (-3125 2225);
PAINT GREEN (-3125 2225);
DISPLAY INVISIBLE (-3125 2225);
FORCEPROP 1 LAST BODY_TYPE PLUMBING
J 2
(-2800 2300);
DISPLAY 1.595745 (-2800 2300);
PAINT GREEN (-2800 2300);
DISPLAY INVISIBLE (-2800 2300);
FORCEPROP 2 LAST CDS_LIB mstr_standard
J 0
(-2800 2350);
PAINT MONO (-2800 2350);
DISPLAY INVISIBLE (-2800 2350);
FORCEPROP 1 LAST PATH I114
J 2
(-2798 2350);
DISPLAY 0.872340 (-2798 2350);
PAINT GREEN (-2798 2350);
DISPLAY INVISIBLE (-2798 2350);
FORCEADD TAP..6
R 2
(-2800 2300);
FORCEPROP 3 LASTPIN (-2850 2300) SIG_NAME M_B_MA<8>
J 0
(-2840 2310);
DISPLAY 0.659574 (-2840 2310);
PAINT MONO (-2840 2310);
DISPLAY INVISIBLE (-2840 2310);
FORCEPROP 1 LASTPIN (-2850 2300) BN 8
J 2
(-2798 2308);
DISPLAY 0.617021 (-2798 2308);
PAINT PINK (-2798 2308);
FORCEPROP 1 LAST HDL_TAP TRUE
J 2
(-3125 2175);
DISPLAY 1.595745 (-3125 2175);
PAINT GREEN (-3125 2175);
DISPLAY INVISIBLE (-3125 2175);
FORCEPROP 1 LAST BODY_TYPE PLUMBING
J 2
(-2800 2250);
DISPLAY 1.595745 (-2800 2250);
PAINT GREEN (-2800 2250);
DISPLAY INVISIBLE (-2800 2250);
FORCEPROP 2 LAST CDS_LIB mstr_standard
J 0
(-2800 2300);
PAINT MONO (-2800 2300);
DISPLAY INVISIBLE (-2800 2300);
FORCEPROP 1 LAST PATH I115
J 2
(-2798 2300);
DISPLAY 0.872340 (-2798 2300);
PAINT GREEN (-2798 2300);
DISPLAY INVISIBLE (-2798 2300);
FORCEADD TAP..6
R 2
(-2800 2250);
FORCEPROP 3 LASTPIN (-2850 2250) SIG_NAME M_B_MA<7>
J 0
(-2840 2260);
DISPLAY 0.659574 (-2840 2260);
PAINT MONO (-2840 2260);
DISPLAY INVISIBLE (-2840 2260);
FORCEPROP 1 LASTPIN (-2850 2250) BN 7
J 2
(-2798 2258);
DISPLAY 0.617021 (-2798 2258);
PAINT PINK (-2798 2258);
FORCEPROP 1 LAST HDL_TAP TRUE
J 2
(-3125 2125);
DISPLAY 1.595745 (-3125 2125);
PAINT GREEN (-3125 2125);
DISPLAY INVISIBLE (-3125 2125);
FORCEPROP 1 LAST BODY_TYPE PLUMBING
J 2
(-2800 2200);
DISPLAY 1.595745 (-2800 2200);
PAINT GREEN (-2800 2200);
DISPLAY INVISIBLE (-2800 2200);
FORCEPROP 2 LAST CDS_LIB mstr_standard
J 0
(-2800 2250);
PAINT MONO (-2800 2250);
DISPLAY INVISIBLE (-2800 2250);
FORCEPROP 1 LAST PATH I116
J 2
(-2798 2250);
DISPLAY 0.872340 (-2798 2250);
PAINT GREEN (-2798 2250);
DISPLAY INVISIBLE (-2798 2250);
FORCEADD TAP..6
R 2
(-2800 2200);
FORCEPROP 3 LASTPIN (-2850 2200) SIG_NAME M_B_MA<6>
J 0
(-2840 2210);
DISPLAY 0.659574 (-2840 2210);
PAINT MONO (-2840 2210);
DISPLAY INVISIBLE (-2840 2210);
FORCEPROP 1 LASTPIN (-2850 2200) BN 6
J 2
(-2798 2208);
DISPLAY 0.617021 (-2798 2208);
PAINT PINK (-2798 2208);
FORCEPROP 1 LAST HDL_TAP TRUE
J 2
(-3125 2075);
DISPLAY 1.595745 (-3125 2075);
PAINT GREEN (-3125 2075);
DISPLAY INVISIBLE (-3125 2075);
FORCEPROP 1 LAST BODY_TYPE PLUMBING
J 2
(-2800 2150);
DISPLAY 1.595745 (-2800 2150);
PAINT GREEN (-2800 2150);
DISPLAY INVISIBLE (-2800 2150);
FORCEPROP 2 LAST CDS_LIB mstr_standard
J 0
(-2800 2200);
PAINT MONO (-2800 2200);
DISPLAY INVISIBLE (-2800 2200);
FORCEPROP 1 LAST PATH I117
J 2
(-2798 2200);
DISPLAY 0.872340 (-2798 2200);
PAINT GREEN (-2798 2200);
DISPLAY INVISIBLE (-2798 2200);
FORCEADD TAP..6
R 2
(-2800 2650);
FORCEPROP 3 LASTPIN (-2850 2650) SIG_NAME M_B_MA<15>
J 0
(-2840 2660);
DISPLAY 0.659574 (-2840 2660);
PAINT MONO (-2840 2660);
DISPLAY INVISIBLE (-2840 2660);
FORCEPROP 1 LASTPIN (-2850 2650) BN 15
J 2
(-2798 2658);
DISPLAY 0.617021 (-2798 2658);
PAINT PINK (-2798 2658);
FORCEPROP 1 LAST HDL_TAP TRUE
J 2
(-3125 2525);
DISPLAY 1.595745 (-3125 2525);
PAINT GREEN (-3125 2525);
DISPLAY INVISIBLE (-3125 2525);
FORCEPROP 1 LAST BODY_TYPE PLUMBING
J 2
(-2800 2600);
DISPLAY 1.595745 (-2800 2600);
PAINT GREEN (-2800 2600);
DISPLAY INVISIBLE (-2800 2600);
FORCEPROP 2 LAST CDS_LIB mstr_standard
J 0
(-2800 2650);
PAINT MONO (-2800 2650);
DISPLAY INVISIBLE (-2800 2650);
FORCEPROP 1 LAST PATH I118
J 2
(-2798 2650);
DISPLAY 0.872340 (-2798 2650);
PAINT GREEN (-2798 2650);
DISPLAY INVISIBLE (-2798 2650);
FORCEADD TAP..6
R 2
(-2800 2600);
FORCEPROP 3 LASTPIN (-2850 2600) SIG_NAME M_B_MA<14>
J 0
(-2840 2610);
DISPLAY 0.659574 (-2840 2610);
PAINT MONO (-2840 2610);
DISPLAY INVISIBLE (-2840 2610);
FORCEPROP 1 LASTPIN (-2850 2600) BN 14
J 2
(-2798 2608);
DISPLAY 0.617021 (-2798 2608);
PAINT PINK (-2798 2608);
FORCEPROP 1 LAST HDL_TAP TRUE
J 2
(-3125 2475);
DISPLAY 1.595745 (-3125 2475);
PAINT GREEN (-3125 2475);
DISPLAY INVISIBLE (-3125 2475);
FORCEPROP 1 LAST BODY_TYPE PLUMBING
J 2
(-2800 2550);
DISPLAY 1.595745 (-2800 2550);
PAINT GREEN (-2800 2550);
DISPLAY INVISIBLE (-2800 2550);
FORCEPROP 2 LAST CDS_LIB mstr_standard
J 0
(-2800 2600);
PAINT MONO (-2800 2600);
DISPLAY INVISIBLE (-2800 2600);
FORCEPROP 1 LAST PATH I119
J 2
(-2798 2600);
DISPLAY 0.872340 (-2798 2600);
PAINT GREEN (-2798 2600);
DISPLAY INVISIBLE (-2798 2600);
FORCEADD TAP..6
(-5525 950);
FORCEPROP 3 LASTPIN (-5475 950) SIG_NAME M_B_CLK_DP<3>
J 0
(-5465 960);
DISPLAY 0.659574 (-5465 960);
PAINT MONO (-5465 960);
DISPLAY INVISIBLE (-5465 960);
FORCEPROP 1 LASTPIN (-5475 950) BN 3
J 0
(-5527 958);
DISPLAY 0.617021 (-5527 958);
PAINT PINK (-5527 958);
FORCEPROP 1 LAST HDL_TAP TRUE
J 0
(-5200 825);
DISPLAY 1.595745 (-5200 825);
PAINT GREEN (-5200 825);
DISPLAY INVISIBLE (-5200 825);
FORCEPROP 1 LAST BODY_TYPE PLUMBING
J 0
(-5525 900);
DISPLAY 1.595745 (-5525 900);
PAINT GREEN (-5525 900);
DISPLAY INVISIBLE (-5525 900);
FORCEPROP 2 LAST CDS_LIB mstr_standard
J 0
(-5525 950);
PAINT MONO (-5525 950);
DISPLAY INVISIBLE (-5525 950);
FORCEPROP 1 LAST PATH I12
J 0
(-5527 950);
DISPLAY 0.872340 (-5527 950);
PAINT GREEN (-5527 950);
DISPLAY INVISIBLE (-5527 950);
FORCEADD TAP..6
R 2
(-2800 2550);
FORCEPROP 3 LASTPIN (-2850 2550) SIG_NAME M_B_MA<13>
J 0
(-2840 2560);
DISPLAY 0.659574 (-2840 2560);
PAINT MONO (-2840 2560);
DISPLAY INVISIBLE (-2840 2560);
FORCEPROP 1 LASTPIN (-2850 2550) BN 13
J 2
(-2798 2558);
DISPLAY 0.617021 (-2798 2558);
PAINT PINK (-2798 2558);
FORCEPROP 1 LAST HDL_TAP TRUE
J 2
(-3125 2425);
DISPLAY 1.595745 (-3125 2425);
PAINT GREEN (-3125 2425);
DISPLAY INVISIBLE (-3125 2425);
FORCEPROP 1 LAST BODY_TYPE PLUMBING
J 2
(-2800 2500);
DISPLAY 1.595745 (-2800 2500);
PAINT GREEN (-2800 2500);
DISPLAY INVISIBLE (-2800 2500);
FORCEPROP 2 LAST CDS_LIB mstr_standard
J 0
(-2800 2550);
PAINT MONO (-2800 2550);
DISPLAY INVISIBLE (-2800 2550);
FORCEPROP 1 LAST PATH I120
J 2
(-2798 2550);
DISPLAY 0.872340 (-2798 2550);
PAINT GREEN (-2798 2550);
DISPLAY INVISIBLE (-2798 2550);
FORCEADD TAP..6
R 2
(-2800 2500);
FORCEPROP 3 LASTPIN (-2850 2500) SIG_NAME M_B_MA<12>
J 0
(-2840 2510);
DISPLAY 0.659574 (-2840 2510);
PAINT MONO (-2840 2510);
DISPLAY INVISIBLE (-2840 2510);
FORCEPROP 1 LASTPIN (-2850 2500) BN 12
J 2
(-2798 2508);
DISPLAY 0.617021 (-2798 2508);
PAINT PINK (-2798 2508);
FORCEPROP 1 LAST HDL_TAP TRUE
J 2
(-3125 2375);
DISPLAY 1.595745 (-3125 2375);
PAINT GREEN (-3125 2375);
DISPLAY INVISIBLE (-3125 2375);
FORCEPROP 1 LAST BODY_TYPE PLUMBING
J 2
(-2800 2450);
DISPLAY 1.595745 (-2800 2450);
PAINT GREEN (-2800 2450);
DISPLAY INVISIBLE (-2800 2450);
FORCEPROP 2 LAST CDS_LIB mstr_standard
J 0
(-2800 2500);
PAINT MONO (-2800 2500);
DISPLAY INVISIBLE (-2800 2500);
FORCEPROP 1 LAST PATH I121
J 2
(-2798 2500);
DISPLAY 0.872340 (-2798 2500);
PAINT GREEN (-2798 2500);
DISPLAY INVISIBLE (-2798 2500);
FORCEADD TAP..6
R 2
(-2800 2450);
FORCEPROP 3 LASTPIN (-2850 2450) SIG_NAME M_B_MA<11>
J 0
(-2840 2460);
DISPLAY 0.659574 (-2840 2460);
PAINT MONO (-2840 2460);
DISPLAY INVISIBLE (-2840 2460);
FORCEPROP 1 LASTPIN (-2850 2450) BN 11
J 2
(-2798 2458);
DISPLAY 0.617021 (-2798 2458);
PAINT PINK (-2798 2458);
FORCEPROP 1 LAST HDL_TAP TRUE
J 2
(-3125 2325);
DISPLAY 1.595745 (-3125 2325);
PAINT GREEN (-3125 2325);
DISPLAY INVISIBLE (-3125 2325);
FORCEPROP 1 LAST BODY_TYPE PLUMBING
J 2
(-2800 2400);
DISPLAY 1.595745 (-2800 2400);
PAINT GREEN (-2800 2400);
DISPLAY INVISIBLE (-2800 2400);
FORCEPROP 2 LAST CDS_LIB mstr_standard
J 0
(-2800 2450);
PAINT MONO (-2800 2450);
DISPLAY INVISIBLE (-2800 2450);
FORCEPROP 1 LAST PATH I122
J 2
(-2798 2450);
DISPLAY 0.872340 (-2798 2450);
PAINT GREEN (-2798 2450);
DISPLAY INVISIBLE (-2798 2450);
FORCEADD TAP..6
R 2
(-2800 2850);
FORCEPROP 3 LASTPIN (-2850 2850) SIG_NAME M_B_DQS_DN<0>
J 0
(-2840 2860);
DISPLAY 0.659574 (-2840 2860);
PAINT MONO (-2840 2860);
DISPLAY INVISIBLE (-2840 2860);
FORCEPROP 1 LASTPIN (-2850 2850) BN 0
J 2
(-2798 2858);
DISPLAY 0.617021 (-2798 2858);
PAINT PINK (-2798 2858);
FORCEPROP 1 LAST HDL_TAP TRUE
J 2
(-3125 2725);
DISPLAY 1.595745 (-3125 2725);
PAINT GREEN (-3125 2725);
DISPLAY INVISIBLE (-3125 2725);
FORCEPROP 1 LAST BODY_TYPE PLUMBING
J 2
(-2800 2800);
DISPLAY 1.595745 (-2800 2800);
PAINT GREEN (-2800 2800);
DISPLAY INVISIBLE (-2800 2800);
FORCEPROP 2 LAST CDS_LIB mstr_standard
J 0
(-2800 2850);
PAINT MONO (-2800 2850);
DISPLAY INVISIBLE (-2800 2850);
FORCEPROP 1 LAST PATH I123
J 2
(-2798 2850);
DISPLAY 0.872340 (-2798 2850);
PAINT GREEN (-2798 2850);
DISPLAY INVISIBLE (-2798 2850);
FORCEADD TAP..6
R 2
(-2800 2900);
FORCEPROP 3 LASTPIN (-2850 2900) SIG_NAME M_B_DQS_DN<1>
J 0
(-2840 2910);
DISPLAY 0.659574 (-2840 2910);
PAINT MONO (-2840 2910);
DISPLAY INVISIBLE (-2840 2910);
FORCEPROP 1 LASTPIN (-2850 2900) BN 1
J 2
(-2798 2908);
DISPLAY 0.617021 (-2798 2908);
PAINT PINK (-2798 2908);
FORCEPROP 1 LAST HDL_TAP TRUE
J 2
(-3125 2775);
DISPLAY 1.595745 (-3125 2775);
PAINT GREEN (-3125 2775);
DISPLAY INVISIBLE (-3125 2775);
FORCEPROP 1 LAST BODY_TYPE PLUMBING
J 2
(-2800 2850);
DISPLAY 1.595745 (-2800 2850);
PAINT GREEN (-2800 2850);
DISPLAY INVISIBLE (-2800 2850);
FORCEPROP 2 LAST CDS_LIB mstr_standard
J 0
(-2800 2900);
PAINT MONO (-2800 2900);
DISPLAY INVISIBLE (-2800 2900);
FORCEPROP 1 LAST PATH I124
J 2
(-2798 2900);
DISPLAY 0.872340 (-2798 2900);
PAINT GREEN (-2798 2900);
DISPLAY INVISIBLE (-2798 2900);
FORCEADD TAP..6
R 2
(-2800 2750);
FORCEPROP 3 LASTPIN (-2850 2750) SIG_NAME M_B_MA<17>
J 0
(-2840 2760);
DISPLAY 0.659574 (-2840 2760);
PAINT MONO (-2840 2760);
DISPLAY INVISIBLE (-2840 2760);
FORCEPROP 1 LASTPIN (-2850 2750) BN 17
J 2
(-2798 2758);
DISPLAY 0.617021 (-2798 2758);
PAINT PINK (-2798 2758);
FORCEPROP 1 LAST HDL_TAP TRUE
J 2
(-3125 2625);
DISPLAY 1.595745 (-3125 2625);
PAINT GREEN (-3125 2625);
DISPLAY INVISIBLE (-3125 2625);
FORCEPROP 1 LAST BODY_TYPE PLUMBING
J 2
(-2800 2700);
DISPLAY 1.595745 (-2800 2700);
PAINT GREEN (-2800 2700);
DISPLAY INVISIBLE (-2800 2700);
FORCEPROP 2 LAST CDS_LIB mstr_standard
J 0
(-2800 2750);
PAINT MONO (-2800 2750);
DISPLAY INVISIBLE (-2800 2750);
FORCEPROP 1 LAST PATH I125
J 2
(-2798 2750);
DISPLAY 0.872340 (-2798 2750);
PAINT GREEN (-2798 2750);
DISPLAY INVISIBLE (-2798 2750);
FORCEADD TAP..6
R 2
(-2800 2700);
FORCEPROP 3 LASTPIN (-2850 2700) SIG_NAME M_B_MA<16>
J 0
(-2840 2710);
DISPLAY 0.659574 (-2840 2710);
PAINT MONO (-2840 2710);
DISPLAY INVISIBLE (-2840 2710);
FORCEPROP 1 LASTPIN (-2850 2700) BN 16
J 2
(-2798 2708);
DISPLAY 0.617021 (-2798 2708);
PAINT PINK (-2798 2708);
FORCEPROP 1 LAST HDL_TAP TRUE
J 2
(-3125 2575);
DISPLAY 1.595745 (-3125 2575);
PAINT GREEN (-3125 2575);
DISPLAY INVISIBLE (-3125 2575);
FORCEPROP 1 LAST BODY_TYPE PLUMBING
J 2
(-2800 2650);
DISPLAY 1.595745 (-2800 2650);
PAINT GREEN (-2800 2650);
DISPLAY INVISIBLE (-2800 2650);
FORCEPROP 2 LAST CDS_LIB mstr_standard
J 0
(-2800 2700);
PAINT MONO (-2800 2700);
DISPLAY INVISIBLE (-2800 2700);
FORCEPROP 1 LAST PATH I126
J 2
(-2798 2700);
DISPLAY 0.872340 (-2798 2700);
PAINT GREEN (-2798 2700);
DISPLAY INVISIBLE (-2798 2700);
FORCEADD TAP..6
R 2
(-2800 2950);
FORCEPROP 3 LASTPIN (-2850 2950) SIG_NAME M_B_DQS_DN<2>
J 0
(-2840 2960);
DISPLAY 0.659574 (-2840 2960);
PAINT MONO (-2840 2960);
DISPLAY INVISIBLE (-2840 2960);
FORCEPROP 1 LASTPIN (-2850 2950) BN 2
J 2
(-2798 2958);
DISPLAY 0.617021 (-2798 2958);
PAINT PINK (-2798 2958);
FORCEPROP 1 LAST HDL_TAP TRUE
J 2
(-3125 2825);
DISPLAY 1.595745 (-3125 2825);
PAINT GREEN (-3125 2825);
DISPLAY INVISIBLE (-3125 2825);
FORCEPROP 1 LAST BODY_TYPE PLUMBING
J 2
(-2800 2900);
DISPLAY 1.595745 (-2800 2900);
PAINT GREEN (-2800 2900);
DISPLAY INVISIBLE (-2800 2900);
FORCEPROP 2 LAST CDS_LIB mstr_standard
J 0
(-2800 2950);
PAINT MONO (-2800 2950);
DISPLAY INVISIBLE (-2800 2950);
FORCEPROP 1 LAST PATH I127
J 2
(-2798 2950);
DISPLAY 0.872340 (-2798 2950);
PAINT GREEN (-2798 2950);
DISPLAY INVISIBLE (-2798 2950);
FORCEADD TAP..6
R 2
(-2800 3000);
FORCEPROP 3 LASTPIN (-2850 3000) SIG_NAME M_B_DQS_DN<3>
J 0
(-2840 3010);
DISPLAY 0.659574 (-2840 3010);
PAINT MONO (-2840 3010);
DISPLAY INVISIBLE (-2840 3010);
FORCEPROP 1 LASTPIN (-2850 3000) BN 3
J 2
(-2798 3008);
DISPLAY 0.617021 (-2798 3008);
PAINT PINK (-2798 3008);
FORCEPROP 1 LAST HDL_TAP TRUE
J 2
(-3125 2875);
DISPLAY 1.595745 (-3125 2875);
PAINT GREEN (-3125 2875);
DISPLAY INVISIBLE (-3125 2875);
FORCEPROP 1 LAST BODY_TYPE PLUMBING
J 2
(-2800 2950);
DISPLAY 1.595745 (-2800 2950);
PAINT GREEN (-2800 2950);
DISPLAY INVISIBLE (-2800 2950);
FORCEPROP 2 LAST CDS_LIB mstr_standard
J 0
(-2800 3000);
PAINT MONO (-2800 3000);
DISPLAY INVISIBLE (-2800 3000);
FORCEPROP 1 LAST PATH I128
J 2
(-2798 3000);
DISPLAY 0.872340 (-2798 3000);
PAINT GREEN (-2798 3000);
DISPLAY INVISIBLE (-2798 3000);
FORCEADD TAP..6
R 2
(-2800 3050);
FORCEPROP 3 LASTPIN (-2850 3050) SIG_NAME M_B_DQS_DN<4>
J 0
(-2840 3060);
DISPLAY 0.659574 (-2840 3060);
PAINT MONO (-2840 3060);
DISPLAY INVISIBLE (-2840 3060);
FORCEPROP 1 LASTPIN (-2850 3050) BN 4
J 2
(-2798 3058);
DISPLAY 0.617021 (-2798 3058);
PAINT PINK (-2798 3058);
FORCEPROP 1 LAST HDL_TAP TRUE
J 2
(-3125 2925);
DISPLAY 1.595745 (-3125 2925);
PAINT GREEN (-3125 2925);
DISPLAY INVISIBLE (-3125 2925);
FORCEPROP 1 LAST BODY_TYPE PLUMBING
J 2
(-2800 3000);
DISPLAY 1.595745 (-2800 3000);
PAINT GREEN (-2800 3000);
DISPLAY INVISIBLE (-2800 3000);
FORCEPROP 2 LAST CDS_LIB mstr_standard
J 0
(-2800 3050);
PAINT MONO (-2800 3050);
DISPLAY INVISIBLE (-2800 3050);
FORCEPROP 1 LAST PATH I129
J 2
(-2798 3050);
DISPLAY 0.872340 (-2798 3050);
PAINT GREEN (-2798 3050);
DISPLAY INVISIBLE (-2798 3050);
FORCEADD TAP..6
(-5525 1050);
FORCEPROP 3 LASTPIN (-5475 1050) SIG_NAME M_B_ECC<0>
J 0
(-5465 1060);
DISPLAY 0.659574 (-5465 1060);
PAINT MONO (-5465 1060);
DISPLAY INVISIBLE (-5465 1060);
FORCEPROP 1 LASTPIN (-5475 1050) BN 0
J 0
(-5527 1058);
DISPLAY 0.617021 (-5527 1058);
PAINT PINK (-5527 1058);
FORCEPROP 1 LAST HDL_TAP TRUE
J 0
(-5200 925);
DISPLAY 1.595745 (-5200 925);
PAINT GREEN (-5200 925);
DISPLAY INVISIBLE (-5200 925);
FORCEPROP 1 LAST BODY_TYPE PLUMBING
J 0
(-5525 1000);
DISPLAY 1.595745 (-5525 1000);
PAINT GREEN (-5525 1000);
DISPLAY INVISIBLE (-5525 1000);
FORCEPROP 2 LAST CDS_LIB mstr_standard
J 0
(-5525 1050);
PAINT MONO (-5525 1050);
DISPLAY INVISIBLE (-5525 1050);
FORCEPROP 1 LAST PATH I13
J 0
(-5527 1050);
DISPLAY 0.872340 (-5527 1050);
PAINT GREEN (-5527 1050);
DISPLAY INVISIBLE (-5527 1050);
FORCEADD TAP..6
R 2
(-2800 3150);
FORCEPROP 3 LASTPIN (-2850 3150) SIG_NAME M_B_DQS_DN<6>
J 0
(-2840 3160);
DISPLAY 0.659574 (-2840 3160);
PAINT MONO (-2840 3160);
DISPLAY INVISIBLE (-2840 3160);
FORCEPROP 1 LASTPIN (-2850 3150) BN 6
J 2
(-2798 3158);
DISPLAY 0.617021 (-2798 3158);
PAINT PINK (-2798 3158);
FORCEPROP 1 LAST HDL_TAP TRUE
J 2
(-3125 3025);
DISPLAY 1.595745 (-3125 3025);
PAINT GREEN (-3125 3025);
DISPLAY INVISIBLE (-3125 3025);
FORCEPROP 1 LAST BODY_TYPE PLUMBING
J 2
(-2800 3100);
DISPLAY 1.595745 (-2800 3100);
PAINT GREEN (-2800 3100);
DISPLAY INVISIBLE (-2800 3100);
FORCEPROP 2 LAST CDS_LIB mstr_standard
J 0
(-2800 3150);
PAINT MONO (-2800 3150);
DISPLAY INVISIBLE (-2800 3150);
FORCEPROP 1 LAST PATH I130
J 2
(-2798 3150);
DISPLAY 0.872340 (-2798 3150);
PAINT GREEN (-2798 3150);
DISPLAY INVISIBLE (-2798 3150);
FORCEADD TAP..6
R 2
(-2800 3200);
FORCEPROP 3 LASTPIN (-2850 3200) SIG_NAME M_B_DQS_DN<7>
J 0
(-2840 3210);
DISPLAY 0.659574 (-2840 3210);
PAINT MONO (-2840 3210);
DISPLAY INVISIBLE (-2840 3210);
FORCEPROP 1 LASTPIN (-2850 3200) BN 7
J 2
(-2798 3208);
DISPLAY 0.617021 (-2798 3208);
PAINT PINK (-2798 3208);
FORCEPROP 1 LAST HDL_TAP TRUE
J 2
(-3125 3075);
DISPLAY 1.595745 (-3125 3075);
PAINT GREEN (-3125 3075);
DISPLAY INVISIBLE (-3125 3075);
FORCEPROP 1 LAST BODY_TYPE PLUMBING
J 2
(-2800 3150);
DISPLAY 1.595745 (-2800 3150);
PAINT GREEN (-2800 3150);
DISPLAY INVISIBLE (-2800 3150);
FORCEPROP 2 LAST CDS_LIB mstr_standard
J 0
(-2800 3200);
PAINT MONO (-2800 3200);
DISPLAY INVISIBLE (-2800 3200);
FORCEPROP 1 LAST PATH I131
J 2
(-2798 3200);
DISPLAY 0.872340 (-2798 3200);
PAINT GREEN (-2798 3200);
DISPLAY INVISIBLE (-2798 3200);
FORCEADD TAP..6
R 2
(-2800 3100);
FORCEPROP 3 LASTPIN (-2850 3100) SIG_NAME M_B_DQS_DN<5>
J 0
(-2840 3110);
DISPLAY 0.659574 (-2840 3110);
PAINT MONO (-2840 3110);
DISPLAY INVISIBLE (-2840 3110);
FORCEPROP 1 LASTPIN (-2850 3100) BN 5
J 2
(-2798 3108);
DISPLAY 0.617021 (-2798 3108);
PAINT PINK (-2798 3108);
FORCEPROP 1 LAST HDL_TAP TRUE
J 2
(-3125 2975);
DISPLAY 1.595745 (-3125 2975);
PAINT GREEN (-3125 2975);
DISPLAY INVISIBLE (-3125 2975);
FORCEPROP 1 LAST BODY_TYPE PLUMBING
J 2
(-2800 3050);
DISPLAY 1.595745 (-2800 3050);
PAINT GREEN (-2800 3050);
DISPLAY INVISIBLE (-2800 3050);
FORCEPROP 2 LAST CDS_LIB mstr_standard
J 0
(-2800 3100);
PAINT MONO (-2800 3100);
DISPLAY INVISIBLE (-2800 3100);
FORCEPROP 1 LAST PATH I132
J 2
(-2798 3100);
DISPLAY 0.872340 (-2798 3100);
PAINT GREEN (-2798 3100);
DISPLAY INVISIBLE (-2798 3100);
FORCEADD TAP..6
R 2
(-2800 3250);
FORCEPROP 3 LASTPIN (-2850 3250) SIG_NAME M_B_DQS_DN<8>
J 0
(-2840 3260);
DISPLAY 0.659574 (-2840 3260);
PAINT MONO (-2840 3260);
DISPLAY INVISIBLE (-2840 3260);
FORCEPROP 1 LASTPIN (-2850 3250) BN 8
J 2
(-2798 3258);
DISPLAY 0.617021 (-2798 3258);
PAINT PINK (-2798 3258);
FORCEPROP 1 LAST HDL_TAP TRUE
J 2
(-3125 3125);
DISPLAY 1.595745 (-3125 3125);
PAINT GREEN (-3125 3125);
DISPLAY INVISIBLE (-3125 3125);
FORCEPROP 1 LAST BODY_TYPE PLUMBING
J 2
(-2800 3200);
DISPLAY 1.595745 (-2800 3200);
PAINT GREEN (-2800 3200);
DISPLAY INVISIBLE (-2800 3200);
FORCEPROP 2 LAST CDS_LIB mstr_standard
J 0
(-2800 3250);
PAINT MONO (-2800 3250);
DISPLAY INVISIBLE (-2800 3250);
FORCEPROP 1 LAST PATH I133
J 2
(-2798 3250);
DISPLAY 0.872340 (-2798 3250);
PAINT GREEN (-2798 3250);
DISPLAY INVISIBLE (-2798 3250);
FORCEADD TAP..6
R 2
(-2800 3450);
FORCEPROP 3 LASTPIN (-2850 3450) SIG_NAME M_B_DQS_DN<12>
J 0
(-2840 3460);
DISPLAY 0.659574 (-2840 3460);
PAINT MONO (-2840 3460);
DISPLAY INVISIBLE (-2840 3460);
FORCEPROP 1 LASTPIN (-2850 3450) BN 12
J 2
(-2798 3458);
DISPLAY 0.617021 (-2798 3458);
PAINT PINK (-2798 3458);
FORCEPROP 1 LAST HDL_TAP TRUE
J 2
(-3125 3325);
DISPLAY 1.595745 (-3125 3325);
PAINT GREEN (-3125 3325);
DISPLAY INVISIBLE (-3125 3325);
FORCEPROP 1 LAST BODY_TYPE PLUMBING
J 2
(-2800 3400);
DISPLAY 1.595745 (-2800 3400);
PAINT GREEN (-2800 3400);
DISPLAY INVISIBLE (-2800 3400);
FORCEPROP 2 LAST CDS_LIB mstr_standard
J 0
(-2800 3450);
PAINT MONO (-2800 3450);
DISPLAY INVISIBLE (-2800 3450);
FORCEPROP 1 LAST PATH I134
J 2
(-2798 3450);
DISPLAY 0.872340 (-2798 3450);
PAINT GREEN (-2798 3450);
DISPLAY INVISIBLE (-2798 3450);
FORCEADD TAP..6
R 2
(-2800 3400);
FORCEPROP 3 LASTPIN (-2850 3400) SIG_NAME M_B_DQS_DN<11>
J 0
(-2840 3410);
DISPLAY 0.659574 (-2840 3410);
PAINT MONO (-2840 3410);
DISPLAY INVISIBLE (-2840 3410);
FORCEPROP 1 LASTPIN (-2850 3400) BN 11
J 2
(-2798 3408);
DISPLAY 0.617021 (-2798 3408);
PAINT PINK (-2798 3408);
FORCEPROP 1 LAST HDL_TAP TRUE
J 2
(-3125 3275);
DISPLAY 1.595745 (-3125 3275);
PAINT GREEN (-3125 3275);
DISPLAY INVISIBLE (-3125 3275);
FORCEPROP 1 LAST BODY_TYPE PLUMBING
J 2
(-2800 3350);
DISPLAY 1.595745 (-2800 3350);
PAINT GREEN (-2800 3350);
DISPLAY INVISIBLE (-2800 3350);
FORCEPROP 2 LAST CDS_LIB mstr_standard
J 0
(-2800 3400);
PAINT MONO (-2800 3400);
DISPLAY INVISIBLE (-2800 3400);
FORCEPROP 1 LAST PATH I135
J 2
(-2798 3400);
DISPLAY 0.872340 (-2798 3400);
PAINT GREEN (-2798 3400);
DISPLAY INVISIBLE (-2798 3400);
FORCEADD TAP..6
R 2
(-2800 3300);
FORCEPROP 3 LASTPIN (-2850 3300) SIG_NAME M_B_DQS_DN<9>
J 0
(-2840 3310);
DISPLAY 0.659574 (-2840 3310);
PAINT MONO (-2840 3310);
DISPLAY INVISIBLE (-2840 3310);
FORCEPROP 1 LASTPIN (-2850 3300) BN 9
J 2
(-2798 3308);
DISPLAY 0.617021 (-2798 3308);
PAINT PINK (-2798 3308);
FORCEPROP 1 LAST HDL_TAP TRUE
J 2
(-3125 3175);
DISPLAY 1.595745 (-3125 3175);
PAINT GREEN (-3125 3175);
DISPLAY INVISIBLE (-3125 3175);
FORCEPROP 1 LAST BODY_TYPE PLUMBING
J 2
(-2800 3250);
DISPLAY 1.595745 (-2800 3250);
PAINT GREEN (-2800 3250);
DISPLAY INVISIBLE (-2800 3250);
FORCEPROP 2 LAST CDS_LIB mstr_standard
J 0
(-2800 3300);
PAINT MONO (-2800 3300);
DISPLAY INVISIBLE (-2800 3300);
FORCEPROP 1 LAST PATH I136
J 2
(-2798 3300);
DISPLAY 0.872340 (-2798 3300);
PAINT GREEN (-2798 3300);
DISPLAY INVISIBLE (-2798 3300);
FORCEADD TAP..6
R 2
(-2800 3350);
FORCEPROP 3 LASTPIN (-2850 3350) SIG_NAME M_B_DQS_DN<10>
J 0
(-2840 3360);
DISPLAY 0.659574 (-2840 3360);
PAINT MONO (-2840 3360);
DISPLAY INVISIBLE (-2840 3360);
FORCEPROP 1 LASTPIN (-2850 3350) BN 10
J 2
(-2798 3358);
DISPLAY 0.617021 (-2798 3358);
PAINT PINK (-2798 3358);
FORCEPROP 1 LAST HDL_TAP TRUE
J 2
(-3125 3225);
DISPLAY 1.595745 (-3125 3225);
PAINT GREEN (-3125 3225);
DISPLAY INVISIBLE (-3125 3225);
FORCEPROP 1 LAST BODY_TYPE PLUMBING
J 2
(-2800 3300);
DISPLAY 1.595745 (-2800 3300);
PAINT GREEN (-2800 3300);
DISPLAY INVISIBLE (-2800 3300);
FORCEPROP 2 LAST CDS_LIB mstr_standard
J 0
(-2800 3350);
PAINT MONO (-2800 3350);
DISPLAY INVISIBLE (-2800 3350);
FORCEPROP 1 LAST PATH I137
J 2
(-2798 3350);
DISPLAY 0.872340 (-2798 3350);
PAINT GREEN (-2798 3350);
DISPLAY INVISIBLE (-2798 3350);
FORCEADD TAP..6
R 2
(-2800 3500);
FORCEPROP 3 LASTPIN (-2850 3500) SIG_NAME M_B_DQS_DN<13>
J 0
(-2840 3510);
DISPLAY 0.659574 (-2840 3510);
PAINT MONO (-2840 3510);
DISPLAY INVISIBLE (-2840 3510);
FORCEPROP 1 LASTPIN (-2850 3500) BN 13
J 2
(-2798 3508);
DISPLAY 0.617021 (-2798 3508);
PAINT PINK (-2798 3508);
FORCEPROP 1 LAST HDL_TAP TRUE
J 2
(-3125 3375);
DISPLAY 1.595745 (-3125 3375);
PAINT GREEN (-3125 3375);
DISPLAY INVISIBLE (-3125 3375);
FORCEPROP 1 LAST BODY_TYPE PLUMBING
J 2
(-2800 3450);
DISPLAY 1.595745 (-2800 3450);
PAINT GREEN (-2800 3450);
DISPLAY INVISIBLE (-2800 3450);
FORCEPROP 2 LAST CDS_LIB mstr_standard
J 0
(-2800 3500);
PAINT MONO (-2800 3500);
DISPLAY INVISIBLE (-2800 3500);
FORCEPROP 1 LAST PATH I138
J 2
(-2798 3500);
DISPLAY 0.872340 (-2798 3500);
PAINT GREEN (-2798 3500);
DISPLAY INVISIBLE (-2798 3500);
FORCEADD TAP..6
R 2
(-2800 3700);
FORCEPROP 3 LASTPIN (-2850 3700) SIG_NAME M_B_DQS_DN<17>
J 0
(-2840 3710);
DISPLAY 0.659574 (-2840 3710);
PAINT MONO (-2840 3710);
DISPLAY INVISIBLE (-2840 3710);
FORCEPROP 1 LASTPIN (-2850 3700) BN 17
J 2
(-2798 3708);
DISPLAY 0.617021 (-2798 3708);
PAINT PINK (-2798 3708);
FORCEPROP 1 LAST HDL_TAP TRUE
J 2
(-3125 3575);
DISPLAY 1.595745 (-3125 3575);
PAINT GREEN (-3125 3575);
DISPLAY INVISIBLE (-3125 3575);
FORCEPROP 1 LAST BODY_TYPE PLUMBING
J 2
(-2800 3650);
DISPLAY 1.595745 (-2800 3650);
PAINT GREEN (-2800 3650);
DISPLAY INVISIBLE (-2800 3650);
FORCEPROP 2 LAST CDS_LIB mstr_standard
J 0
(-2800 3700);
PAINT MONO (-2800 3700);
DISPLAY INVISIBLE (-2800 3700);
FORCEPROP 1 LAST PATH I139
J 2
(-2798 3700);
DISPLAY 0.872340 (-2798 3700);
PAINT GREEN (-2798 3700);
DISPLAY INVISIBLE (-2798 3700);
FORCEADD TAP..6
(-5525 1100);
FORCEPROP 3 LASTPIN (-5475 1100) SIG_NAME M_B_ECC<1>
J 0
(-5465 1110);
DISPLAY 0.659574 (-5465 1110);
PAINT MONO (-5465 1110);
DISPLAY INVISIBLE (-5465 1110);
FORCEPROP 1 LASTPIN (-5475 1100) BN 1
J 0
(-5527 1108);
DISPLAY 0.617021 (-5527 1108);
PAINT PINK (-5527 1108);
FORCEPROP 1 LAST HDL_TAP TRUE
J 0
(-5200 975);
DISPLAY 1.595745 (-5200 975);
PAINT GREEN (-5200 975);
DISPLAY INVISIBLE (-5200 975);
FORCEPROP 1 LAST BODY_TYPE PLUMBING
J 0
(-5525 1050);
DISPLAY 1.595745 (-5525 1050);
PAINT GREEN (-5525 1050);
DISPLAY INVISIBLE (-5525 1050);
FORCEPROP 2 LAST CDS_LIB mstr_standard
J 0
(-5525 1100);
PAINT MONO (-5525 1100);
DISPLAY INVISIBLE (-5525 1100);
FORCEPROP 1 LAST PATH I14
J 0
(-5527 1100);
DISPLAY 0.872340 (-5527 1100);
PAINT GREEN (-5527 1100);
DISPLAY INVISIBLE (-5527 1100);
FORCEADD TAP..6
R 2
(-2800 3650);
FORCEPROP 3 LASTPIN (-2850 3650) SIG_NAME M_B_DQS_DN<16>
J 0
(-2840 3660);
DISPLAY 0.659574 (-2840 3660);
PAINT MONO (-2840 3660);
DISPLAY INVISIBLE (-2840 3660);
FORCEPROP 1 LASTPIN (-2850 3650) BN 16
J 2
(-2798 3658);
DISPLAY 0.617021 (-2798 3658);
PAINT PINK (-2798 3658);
FORCEPROP 1 LAST HDL_TAP TRUE
J 2
(-3125 3525);
DISPLAY 1.595745 (-3125 3525);
PAINT GREEN (-3125 3525);
DISPLAY INVISIBLE (-3125 3525);
FORCEPROP 1 LAST BODY_TYPE PLUMBING
J 2
(-2800 3600);
DISPLAY 1.595745 (-2800 3600);
PAINT GREEN (-2800 3600);
DISPLAY INVISIBLE (-2800 3600);
FORCEPROP 2 LAST CDS_LIB mstr_standard
J 0
(-2800 3650);
PAINT MONO (-2800 3650);
DISPLAY INVISIBLE (-2800 3650);
FORCEPROP 1 LAST PATH I140
J 2
(-2798 3650);
DISPLAY 0.872340 (-2798 3650);
PAINT GREEN (-2798 3650);
DISPLAY INVISIBLE (-2798 3650);
FORCEADD TAP..6
R 2
(-2800 3600);
FORCEPROP 3 LASTPIN (-2850 3600) SIG_NAME M_B_DQS_DN<15>
J 0
(-2840 3610);
DISPLAY 0.659574 (-2840 3610);
PAINT MONO (-2840 3610);
DISPLAY INVISIBLE (-2840 3610);
FORCEPROP 1 LASTPIN (-2850 3600) BN 15
J 2
(-2798 3608);
DISPLAY 0.617021 (-2798 3608);
PAINT PINK (-2798 3608);
FORCEPROP 1 LAST HDL_TAP TRUE
J 2
(-3125 3475);
DISPLAY 1.595745 (-3125 3475);
PAINT GREEN (-3125 3475);
DISPLAY INVISIBLE (-3125 3475);
FORCEPROP 1 LAST BODY_TYPE PLUMBING
J 2
(-2800 3550);
DISPLAY 1.595745 (-2800 3550);
PAINT GREEN (-2800 3550);
DISPLAY INVISIBLE (-2800 3550);
FORCEPROP 2 LAST CDS_LIB mstr_standard
J 0
(-2800 3600);
PAINT MONO (-2800 3600);
DISPLAY INVISIBLE (-2800 3600);
FORCEPROP 1 LAST PATH I141
J 2
(-2798 3600);
DISPLAY 0.872340 (-2798 3600);
PAINT GREEN (-2798 3600);
DISPLAY INVISIBLE (-2798 3600);
FORCEADD TAP..6
R 2
(-2800 3550);
FORCEPROP 3 LASTPIN (-2850 3550) SIG_NAME M_B_DQS_DN<14>
J 0
(-2840 3560);
DISPLAY 0.659574 (-2840 3560);
PAINT MONO (-2840 3560);
DISPLAY INVISIBLE (-2840 3560);
FORCEPROP 1 LASTPIN (-2850 3550) BN 14
J 2
(-2798 3558);
DISPLAY 0.617021 (-2798 3558);
PAINT PINK (-2798 3558);
FORCEPROP 1 LAST HDL_TAP TRUE
J 2
(-3125 3425);
DISPLAY 1.595745 (-3125 3425);
PAINT GREEN (-3125 3425);
DISPLAY INVISIBLE (-3125 3425);
FORCEPROP 1 LAST BODY_TYPE PLUMBING
J 2
(-2800 3500);
DISPLAY 1.595745 (-2800 3500);
PAINT GREEN (-2800 3500);
DISPLAY INVISIBLE (-2800 3500);
FORCEPROP 2 LAST CDS_LIB mstr_standard
J 0
(-2800 3550);
PAINT MONO (-2800 3550);
DISPLAY INVISIBLE (-2800 3550);
FORCEPROP 1 LAST PATH I142
J 2
(-2798 3550);
DISPLAY 0.872340 (-2798 3550);
PAINT GREEN (-2798 3550);
DISPLAY INVISIBLE (-2798 3550);
FORCEADD TAP..6
R 2
(-2800 3800);
FORCEPROP 3 LASTPIN (-2850 3800) SIG_NAME M_B_DQS_DP<0>
J 0
(-2840 3810);
DISPLAY 0.659574 (-2840 3810);
PAINT MONO (-2840 3810);
DISPLAY INVISIBLE (-2840 3810);
FORCEPROP 1 LASTPIN (-2850 3800) BN 0
J 2
(-2798 3808);
DISPLAY 0.617021 (-2798 3808);
PAINT PINK (-2798 3808);
FORCEPROP 1 LAST HDL_TAP TRUE
J 2
(-3125 3675);
DISPLAY 1.595745 (-3125 3675);
PAINT GREEN (-3125 3675);
DISPLAY INVISIBLE (-3125 3675);
FORCEPROP 1 LAST BODY_TYPE PLUMBING
J 2
(-2800 3750);
DISPLAY 1.595745 (-2800 3750);
PAINT GREEN (-2800 3750);
DISPLAY INVISIBLE (-2800 3750);
FORCEPROP 2 LAST CDS_LIB mstr_standard
J 0
(-2800 3800);
PAINT MONO (-2800 3800);
DISPLAY INVISIBLE (-2800 3800);
FORCEPROP 1 LAST PATH I143
J 2
(-2798 3800);
DISPLAY 0.872340 (-2798 3800);
PAINT GREEN (-2798 3800);
DISPLAY INVISIBLE (-2798 3800);
FORCEADD TAP..6
R 2
(-2800 3900);
FORCEPROP 3 LASTPIN (-2850 3900) SIG_NAME M_B_DQS_DP<2>
J 0
(-2840 3910);
DISPLAY 0.659574 (-2840 3910);
PAINT MONO (-2840 3910);
DISPLAY INVISIBLE (-2840 3910);
FORCEPROP 1 LASTPIN (-2850 3900) BN 2
J 2
(-2798 3908);
DISPLAY 0.617021 (-2798 3908);
PAINT PINK (-2798 3908);
FORCEPROP 1 LAST HDL_TAP TRUE
J 2
(-3125 3775);
DISPLAY 1.595745 (-3125 3775);
PAINT GREEN (-3125 3775);
DISPLAY INVISIBLE (-3125 3775);
FORCEPROP 1 LAST BODY_TYPE PLUMBING
J 2
(-2800 3850);
DISPLAY 1.595745 (-2800 3850);
PAINT GREEN (-2800 3850);
DISPLAY INVISIBLE (-2800 3850);
FORCEPROP 2 LAST CDS_LIB mstr_standard
J 0
(-2800 3900);
PAINT MONO (-2800 3900);
DISPLAY INVISIBLE (-2800 3900);
FORCEPROP 1 LAST PATH I144
J 2
(-2798 3900);
DISPLAY 0.872340 (-2798 3900);
PAINT GREEN (-2798 3900);
DISPLAY INVISIBLE (-2798 3900);
FORCEADD TAP..6
R 2
(-2800 3950);
FORCEPROP 3 LASTPIN (-2850 3950) SIG_NAME M_B_DQS_DP<3>
J 0
(-2840 3960);
DISPLAY 0.659574 (-2840 3960);
PAINT MONO (-2840 3960);
DISPLAY INVISIBLE (-2840 3960);
FORCEPROP 1 LASTPIN (-2850 3950) BN 3
J 2
(-2798 3958);
DISPLAY 0.617021 (-2798 3958);
PAINT PINK (-2798 3958);
FORCEPROP 1 LAST HDL_TAP TRUE
J 2
(-3125 3825);
DISPLAY 1.595745 (-3125 3825);
PAINT GREEN (-3125 3825);
DISPLAY INVISIBLE (-3125 3825);
FORCEPROP 1 LAST BODY_TYPE PLUMBING
J 2
(-2800 3900);
DISPLAY 1.595745 (-2800 3900);
PAINT GREEN (-2800 3900);
DISPLAY INVISIBLE (-2800 3900);
FORCEPROP 2 LAST CDS_LIB mstr_standard
J 0
(-2800 3950);
PAINT MONO (-2800 3950);
DISPLAY INVISIBLE (-2800 3950);
FORCEPROP 1 LAST PATH I145
J 2
(-2798 3950);
DISPLAY 0.872340 (-2798 3950);
PAINT GREEN (-2798 3950);
DISPLAY INVISIBLE (-2798 3950);
FORCEADD TAP..6
R 2
(-2800 3850);
FORCEPROP 3 LASTPIN (-2850 3850) SIG_NAME M_B_DQS_DP<1>
J 0
(-2840 3860);
DISPLAY 0.659574 (-2840 3860);
PAINT MONO (-2840 3860);
DISPLAY INVISIBLE (-2840 3860);
FORCEPROP 1 LASTPIN (-2850 3850) BN 1
J 2
(-2798 3858);
DISPLAY 0.617021 (-2798 3858);
PAINT PINK (-2798 3858);
FORCEPROP 1 LAST HDL_TAP TRUE
J 2
(-3125 3725);
DISPLAY 1.595745 (-3125 3725);
PAINT GREEN (-3125 3725);
DISPLAY INVISIBLE (-3125 3725);
FORCEPROP 1 LAST BODY_TYPE PLUMBING
J 2
(-2800 3800);
DISPLAY 1.595745 (-2800 3800);
PAINT GREEN (-2800 3800);
DISPLAY INVISIBLE (-2800 3800);
FORCEPROP 2 LAST CDS_LIB mstr_standard
J 0
(-2800 3850);
PAINT MONO (-2800 3850);
DISPLAY INVISIBLE (-2800 3850);
FORCEPROP 1 LAST PATH I146
J 2
(-2798 3850);
DISPLAY 0.872340 (-2798 3850);
PAINT GREEN (-2798 3850);
DISPLAY INVISIBLE (-2798 3850);
FORCEADD OFFPAGE..2
(-1950 500);
FORCEPROP 2 LAST $XR1 46 
J 0
(-1671 500);
DISPLAY 0.638298 (-1671 500);
PAINT MONO (-1671 500);
FORCEPROP 2 LAST $XR0 45 
J 0
(-1761 500);
DISPLAY 0.638298 (-1761 500);
PAINT MONO (-1761 500);
FORCEPROP 1 LAST COMMENT_BODY TRUE
J 0
(-1995 405);
DISPLAY 1.170213 (-1995 405);
PAINT GREEN (-1995 405);
DISPLAY INVISIBLE (-1995 405);
FORCEPROP 1 LAST OFFPAGE TRUE
J 0
(-1625 375);
DISPLAY 1.170213 (-1625 375);
PAINT GREEN (-1625 375);
DISPLAY INVISIBLE (-1625 375);
FORCEPROP 2 LAST CDS_LIB mstr_standard
J 0
(-1950 500);
PAINT MONO (-1950 500);
DISPLAY INVISIBLE (-1950 500);
FORCEPROP 2 LAST PATH I147
J 0
(-1775 575);
DISPLAY 1.021277 (-1775 575);
PAINT ORANGE (-1775 575);
DISPLAY INVISIBLE (-1775 575);
FORCEADD OFFPAGE..4
(-1950 550);
FORCEPROP 2 LAST $XR1 46 
J 0
(-1674 550);
DISPLAY 0.638298 (-1674 550);
PAINT MONO (-1674 550);
FORCEPROP 2 LAST $XR0 45 
J 0
(-1764 550);
DISPLAY 0.638298 (-1764 550);
PAINT MONO (-1764 550);
FORCEPROP 1 LAST COMMENT_BODY TRUE
J 0
(-1975 450);
DISPLAY 1.170213 (-1975 450);
PAINT GREEN (-1975 450);
DISPLAY INVISIBLE (-1975 450);
FORCEPROP 1 LAST OFFPAGE TRUE
J 0
(-1625 425);
DISPLAY 1.170213 (-1625 425);
PAINT GREEN (-1625 425);
DISPLAY INVISIBLE (-1625 425);
FORCEPROP 2 LAST CDS_LIB mstr_standard
J 0
(-1950 550);
PAINT MONO (-1950 550);
DISPLAY INVISIBLE (-1950 550);
FORCEPROP 2 LAST PATH I148
J 0
(-1775 625);
DISPLAY 1.021277 (-1775 625);
PAINT ORANGE (-1775 625);
DISPLAY INVISIBLE (-1775 625);
FORCEADD OFFPAGE..2
(-1950 600);
FORCEPROP 2 LAST $XR1 46 
J 0
(-1671 600);
DISPLAY 0.638298 (-1671 600);
PAINT MONO (-1671 600);
FORCEPROP 2 LAST $XR0 45 
J 0
(-1761 600);
DISPLAY 0.638298 (-1761 600);
PAINT MONO (-1761 600);
FORCEPROP 1 LAST COMMENT_BODY TRUE
J 0
(-1995 505);
DISPLAY 1.170213 (-1995 505);
PAINT GREEN (-1995 505);
DISPLAY INVISIBLE (-1995 505);
FORCEPROP 1 LAST OFFPAGE TRUE
J 0
(-1625 475);
DISPLAY 1.170213 (-1625 475);
PAINT GREEN (-1625 475);
DISPLAY INVISIBLE (-1625 475);
FORCEPROP 2 LAST CDS_LIB mstr_standard
J 0
(-1950 600);
PAINT MONO (-1950 600);
DISPLAY INVISIBLE (-1950 600);
FORCEPROP 2 LAST PATH I149
J 0
(-1775 675);
DISPLAY 1.021277 (-1775 675);
PAINT ORANGE (-1775 675);
DISPLAY INVISIBLE (-1775 675);
FORCEADD TAP..6
(-5525 1150);
FORCEPROP 3 LASTPIN (-5475 1150) SIG_NAME M_B_ECC<2>
J 0
(-5465 1160);
DISPLAY 0.659574 (-5465 1160);
PAINT MONO (-5465 1160);
DISPLAY INVISIBLE (-5465 1160);
FORCEPROP 1 LASTPIN (-5475 1150) BN 2
J 0
(-5527 1158);
DISPLAY 0.617021 (-5527 1158);
PAINT PINK (-5527 1158);
FORCEPROP 1 LAST HDL_TAP TRUE
J 0
(-5200 1025);
DISPLAY 1.595745 (-5200 1025);
PAINT GREEN (-5200 1025);
DISPLAY INVISIBLE (-5200 1025);
FORCEPROP 1 LAST BODY_TYPE PLUMBING
J 0
(-5525 1100);
DISPLAY 1.595745 (-5525 1100);
PAINT GREEN (-5525 1100);
DISPLAY INVISIBLE (-5525 1100);
FORCEPROP 2 LAST CDS_LIB mstr_standard
J 0
(-5525 1150);
PAINT MONO (-5525 1150);
DISPLAY INVISIBLE (-5525 1150);
FORCEPROP 1 LAST PATH I15
J 0
(-5527 1150);
DISPLAY 0.872340 (-5527 1150);
PAINT GREEN (-5527 1150);
DISPLAY INVISIBLE (-5527 1150);
FORCEADD OFFPAGE..2
(-1950 800);
FORCEPROP 2 LAST $XR1 46 
J 0
(-1671 800);
DISPLAY 0.638298 (-1671 800);
PAINT MONO (-1671 800);
FORCEPROP 2 LAST $XR0 45 
J 0
(-1761 800);
DISPLAY 0.638298 (-1761 800);
PAINT MONO (-1761 800);
FORCEPROP 1 LAST COMMENT_BODY TRUE
J 0
(-1995 705);
DISPLAY 1.170213 (-1995 705);
PAINT GREEN (-1995 705);
DISPLAY INVISIBLE (-1995 705);
FORCEPROP 1 LAST OFFPAGE TRUE
J 0
(-1625 675);
DISPLAY 1.170213 (-1625 675);
PAINT GREEN (-1625 675);
DISPLAY INVISIBLE (-1625 675);
FORCEPROP 2 LAST CDS_LIB mstr_standard
J 0
(-1950 800);
PAINT MONO (-1950 800);
DISPLAY INVISIBLE (-1950 800);
FORCEPROP 2 LAST PATH I150
J 0
(-1775 875);
DISPLAY 1.021277 (-1775 875);
PAINT ORANGE (-1775 875);
DISPLAY INVISIBLE (-1775 875);
FORCEADD OFFPAGE..2
(-1950 900);
FORCEPROP 2 LAST $XR1 46 
J 0
(-1671 900);
DISPLAY 0.638298 (-1671 900);
PAINT MONO (-1671 900);
FORCEPROP 2 LAST $XR0 45 
J 0
(-1761 900);
DISPLAY 0.638298 (-1761 900);
PAINT MONO (-1761 900);
FORCEPROP 1 LAST COMMENT_BODY TRUE
J 0
(-1995 805);
DISPLAY 1.170213 (-1995 805);
PAINT GREEN (-1995 805);
DISPLAY INVISIBLE (-1995 805);
FORCEPROP 1 LAST OFFPAGE TRUE
J 0
(-1625 775);
DISPLAY 1.170213 (-1625 775);
PAINT GREEN (-1625 775);
DISPLAY INVISIBLE (-1625 775);
FORCEPROP 2 LAST CDS_LIB mstr_standard
J 0
(-1950 900);
PAINT MONO (-1950 900);
DISPLAY INVISIBLE (-1950 900);
FORCEPROP 2 LAST PATH I151
J 0
(-1775 975);
DISPLAY 1.021277 (-1775 975);
PAINT ORANGE (-1775 975);
DISPLAY INVISIBLE (-1775 975);
FORCEADD OFFPAGE..2
(-1950 1350);
FORCEPROP 2 LAST $XR1 46 
J 0
(-1671 1350);
DISPLAY 0.638298 (-1671 1350);
PAINT MONO (-1671 1350);
FORCEPROP 2 LAST $XR0 45 
J 0
(-1761 1350);
DISPLAY 0.638298 (-1761 1350);
PAINT MONO (-1761 1350);
FORCEPROP 1 LAST COMMENT_BODY TRUE
J 0
(-1995 1255);
DISPLAY 1.170213 (-1995 1255);
PAINT GREEN (-1995 1255);
DISPLAY INVISIBLE (-1995 1255);
FORCEPROP 1 LAST OFFPAGE TRUE
J 0
(-1625 1225);
DISPLAY 1.170213 (-1625 1225);
PAINT GREEN (-1625 1225);
DISPLAY INVISIBLE (-1625 1225);
FORCEPROP 2 LAST CDS_LIB mstr_standard
J 0
(-1950 1350);
PAINT MONO (-1950 1350);
DISPLAY INVISIBLE (-1950 1350);
FORCEPROP 2 LAST PATH I152
J 0
(-1775 1425);
DISPLAY 1.021277 (-1775 1425);
PAINT ORANGE (-1775 1425);
DISPLAY INVISIBLE (-1775 1425);
FORCEADD OFFPAGE..2
(-1950 1600);
FORCEPROP 2 LAST $XR1 46 
J 0
(-1671 1600);
DISPLAY 0.638298 (-1671 1600);
PAINT MONO (-1671 1600);
FORCEPROP 2 LAST $XR0 45 
J 0
(-1761 1600);
DISPLAY 0.638298 (-1761 1600);
PAINT MONO (-1761 1600);
FORCEPROP 1 LAST COMMENT_BODY TRUE
J 0
(-1995 1505);
DISPLAY 1.170213 (-1995 1505);
PAINT GREEN (-1995 1505);
DISPLAY INVISIBLE (-1995 1505);
FORCEPROP 1 LAST OFFPAGE TRUE
J 0
(-1625 1475);
DISPLAY 1.170213 (-1625 1475);
PAINT GREEN (-1625 1475);
DISPLAY INVISIBLE (-1625 1475);
FORCEPROP 2 LAST CDS_LIB mstr_standard
J 0
(-1950 1600);
PAINT MONO (-1950 1600);
DISPLAY INVISIBLE (-1950 1600);
FORCEPROP 2 LAST PATH I153
J 0
(-1775 1675);
DISPLAY 1.021277 (-1775 1675);
PAINT ORANGE (-1775 1675);
DISPLAY INVISIBLE (-1775 1675);
FORCEADD OFFPAGE..2
(-1950 1850);
FORCEPROP 2 LAST $XR1 46 
J 0
(-1671 1850);
DISPLAY 0.638298 (-1671 1850);
PAINT MONO (-1671 1850);
FORCEPROP 2 LAST $XR0 45 
J 0
(-1761 1850);
DISPLAY 0.638298 (-1761 1850);
PAINT MONO (-1761 1850);
FORCEPROP 1 LAST COMMENT_BODY TRUE
J 0
(-1995 1755);
DISPLAY 1.170213 (-1995 1755);
PAINT GREEN (-1995 1755);
DISPLAY INVISIBLE (-1995 1755);
FORCEPROP 1 LAST OFFPAGE TRUE
J 0
(-1625 1725);
DISPLAY 1.170213 (-1625 1725);
PAINT GREEN (-1625 1725);
DISPLAY INVISIBLE (-1625 1725);
FORCEPROP 2 LAST CDS_LIB mstr_standard
J 0
(-1950 1850);
PAINT MONO (-1950 1850);
DISPLAY INVISIBLE (-1950 1850);
FORCEPROP 2 LAST PATH I154
J 0
(-1775 1925);
DISPLAY 1.021277 (-1775 1925);
PAINT ORANGE (-1775 1925);
DISPLAY INVISIBLE (-1775 1925);
FORCEADD OFFPAGE..2
(-1950 2800);
FORCEPROP 2 LAST $XR1 46 
J 0
(-1671 2800);
DISPLAY 0.638298 (-1671 2800);
PAINT MONO (-1671 2800);
FORCEPROP 2 LAST $XR0 45 
J 0
(-1761 2800);
DISPLAY 0.638298 (-1761 2800);
PAINT MONO (-1761 2800);
FORCEPROP 1 LAST COMMENT_BODY TRUE
J 0
(-1995 2705);
DISPLAY 1.170213 (-1995 2705);
PAINT GREEN (-1995 2705);
DISPLAY INVISIBLE (-1995 2705);
FORCEPROP 1 LAST OFFPAGE TRUE
J 0
(-1625 2675);
DISPLAY 1.170213 (-1625 2675);
PAINT GREEN (-1625 2675);
DISPLAY INVISIBLE (-1625 2675);
FORCEPROP 2 LAST CDS_LIB mstr_standard
J 0
(-1950 2800);
PAINT MONO (-1950 2800);
DISPLAY INVISIBLE (-1950 2800);
FORCEPROP 2 LAST PATH I155
J 0
(-1775 2875);
DISPLAY 1.021277 (-1775 2875);
PAINT ORANGE (-1775 2875);
DISPLAY INVISIBLE (-1775 2875);
FORCEADD OFFPAGE..3
(-1950 3750);
FORCEPROP 2 LAST $XR1 46 
J 0
(-1646 3750);
DISPLAY 0.638298 (-1646 3750);
PAINT MONO (-1646 3750);
FORCEPROP 2 LAST $XR0 45 
J 0
(-1736 3750);
DISPLAY 0.638298 (-1736 3750);
PAINT MONO (-1736 3750);
FORCEPROP 1 LAST COMMENT_BODY TRUE
J 0
(-2000 3650);
DISPLAY 1.170213 (-2000 3650);
PAINT GREEN (-2000 3650);
DISPLAY INVISIBLE (-2000 3650);
FORCEPROP 1 LAST OFFPAGE TRUE
J 0
(-1625 3625);
DISPLAY 1.170213 (-1625 3625);
PAINT GREEN (-1625 3625);
DISPLAY INVISIBLE (-1625 3625);
FORCEPROP 2 LAST CDS_LIB mstr_standard
J 0
(-1950 3750);
PAINT MONO (-1950 3750);
DISPLAY INVISIBLE (-1950 3750);
FORCEPROP 2 LAST PATH I156
J 0
(-1750 3825);
DISPLAY 1.021277 (-1750 3825);
PAINT ORANGE (-1750 3825);
DISPLAY INVISIBLE (-1750 3825);
FORCEADD TAP..6
R 2
(-2800 4150);
FORCEPROP 3 LASTPIN (-2850 4150) SIG_NAME M_B_DQS_DP<7>
J 0
(-2840 4160);
DISPLAY 0.659574 (-2840 4160);
PAINT MONO (-2840 4160);
DISPLAY INVISIBLE (-2840 4160);
FORCEPROP 1 LASTPIN (-2850 4150) BN 7
J 2
(-2798 4158);
DISPLAY 0.617021 (-2798 4158);
PAINT PINK (-2798 4158);
FORCEPROP 1 LAST HDL_TAP TRUE
J 2
(-3125 4025);
DISPLAY 1.595745 (-3125 4025);
PAINT GREEN (-3125 4025);
DISPLAY INVISIBLE (-3125 4025);
FORCEPROP 1 LAST BODY_TYPE PLUMBING
J 2
(-2800 4100);
DISPLAY 1.595745 (-2800 4100);
PAINT GREEN (-2800 4100);
DISPLAY INVISIBLE (-2800 4100);
FORCEPROP 2 LAST CDS_LIB mstr_standard
J 0
(-2800 4150);
PAINT MONO (-2800 4150);
DISPLAY INVISIBLE (-2800 4150);
FORCEPROP 1 LAST PATH I157
J 2
(-2798 4150);
DISPLAY 0.872340 (-2798 4150);
PAINT GREEN (-2798 4150);
DISPLAY INVISIBLE (-2798 4150);
FORCEADD TAP..6
R 2
(-2800 4200);
FORCEPROP 3 LASTPIN (-2850 4200) SIG_NAME M_B_DQS_DP<8>
J 0
(-2840 4210);
DISPLAY 0.659574 (-2840 4210);
PAINT MONO (-2840 4210);
DISPLAY INVISIBLE (-2840 4210);
FORCEPROP 1 LASTPIN (-2850 4200) BN 8
J 2
(-2798 4208);
DISPLAY 0.617021 (-2798 4208);
PAINT PINK (-2798 4208);
FORCEPROP 1 LAST HDL_TAP TRUE
J 2
(-3125 4075);
DISPLAY 1.595745 (-3125 4075);
PAINT GREEN (-3125 4075);
DISPLAY INVISIBLE (-3125 4075);
FORCEPROP 1 LAST BODY_TYPE PLUMBING
J 2
(-2800 4150);
DISPLAY 1.595745 (-2800 4150);
PAINT GREEN (-2800 4150);
DISPLAY INVISIBLE (-2800 4150);
FORCEPROP 2 LAST CDS_LIB mstr_standard
J 0
(-2800 4200);
PAINT MONO (-2800 4200);
DISPLAY INVISIBLE (-2800 4200);
FORCEPROP 1 LAST PATH I158
J 2
(-2798 4200);
DISPLAY 0.872340 (-2798 4200);
PAINT GREEN (-2798 4200);
DISPLAY INVISIBLE (-2798 4200);
FORCEADD TAP..6
R 2
(-2800 4050);
FORCEPROP 3 LASTPIN (-2850 4050) SIG_NAME M_B_DQS_DP<5>
J 0
(-2840 4060);
DISPLAY 0.659574 (-2840 4060);
PAINT MONO (-2840 4060);
DISPLAY INVISIBLE (-2840 4060);
FORCEPROP 1 LASTPIN (-2850 4050) BN 5
J 2
(-2798 4058);
DISPLAY 0.617021 (-2798 4058);
PAINT PINK (-2798 4058);
FORCEPROP 1 LAST HDL_TAP TRUE
J 2
(-3125 3925);
DISPLAY 1.595745 (-3125 3925);
PAINT GREEN (-3125 3925);
DISPLAY INVISIBLE (-3125 3925);
FORCEPROP 1 LAST BODY_TYPE PLUMBING
J 2
(-2800 4000);
DISPLAY 1.595745 (-2800 4000);
PAINT GREEN (-2800 4000);
DISPLAY INVISIBLE (-2800 4000);
FORCEPROP 2 LAST CDS_LIB mstr_standard
J 0
(-2800 4050);
PAINT MONO (-2800 4050);
DISPLAY INVISIBLE (-2800 4050);
FORCEPROP 1 LAST PATH I159
J 2
(-2798 4050);
DISPLAY 0.872340 (-2798 4050);
PAINT GREEN (-2798 4050);
DISPLAY INVISIBLE (-2798 4050);
FORCEADD TAP..6
(-5525 1250);
FORCEPROP 3 LASTPIN (-5475 1250) SIG_NAME M_B_ECC<4>
J 0
(-5465 1260);
DISPLAY 0.659574 (-5465 1260);
PAINT MONO (-5465 1260);
DISPLAY INVISIBLE (-5465 1260);
FORCEPROP 1 LASTPIN (-5475 1250) BN 4
J 0
(-5527 1258);
DISPLAY 0.617021 (-5527 1258);
PAINT PINK (-5527 1258);
FORCEPROP 1 LAST HDL_TAP TRUE
J 0
(-5200 1125);
DISPLAY 1.595745 (-5200 1125);
PAINT GREEN (-5200 1125);
DISPLAY INVISIBLE (-5200 1125);
FORCEPROP 1 LAST BODY_TYPE PLUMBING
J 0
(-5525 1200);
DISPLAY 1.595745 (-5525 1200);
PAINT GREEN (-5525 1200);
DISPLAY INVISIBLE (-5525 1200);
FORCEPROP 2 LAST CDS_LIB mstr_standard
J 0
(-5525 1250);
PAINT MONO (-5525 1250);
DISPLAY INVISIBLE (-5525 1250);
FORCEPROP 1 LAST PATH I16
J 0
(-5527 1250);
DISPLAY 0.872340 (-5527 1250);
PAINT GREEN (-5527 1250);
DISPLAY INVISIBLE (-5527 1250);
FORCEADD TAP..6
R 2
(-2800 4100);
FORCEPROP 3 LASTPIN (-2850 4100) SIG_NAME M_B_DQS_DP<6>
J 0
(-2840 4110);
DISPLAY 0.659574 (-2840 4110);
PAINT MONO (-2840 4110);
DISPLAY INVISIBLE (-2840 4110);
FORCEPROP 1 LASTPIN (-2850 4100) BN 6
J 2
(-2798 4108);
DISPLAY 0.617021 (-2798 4108);
PAINT PINK (-2798 4108);
FORCEPROP 1 LAST HDL_TAP TRUE
J 2
(-3125 3975);
DISPLAY 1.595745 (-3125 3975);
PAINT GREEN (-3125 3975);
DISPLAY INVISIBLE (-3125 3975);
FORCEPROP 1 LAST BODY_TYPE PLUMBING
J 2
(-2800 4050);
DISPLAY 1.595745 (-2800 4050);
PAINT GREEN (-2800 4050);
DISPLAY INVISIBLE (-2800 4050);
FORCEPROP 2 LAST CDS_LIB mstr_standard
J 0
(-2800 4100);
PAINT MONO (-2800 4100);
DISPLAY INVISIBLE (-2800 4100);
FORCEPROP 1 LAST PATH I160
J 2
(-2798 4100);
DISPLAY 0.872340 (-2798 4100);
PAINT GREEN (-2798 4100);
DISPLAY INVISIBLE (-2798 4100);
FORCEADD TAP..6
R 2
(-2800 4000);
FORCEPROP 3 LASTPIN (-2850 4000) SIG_NAME M_B_DQS_DP<4>
J 0
(-2840 4010);
DISPLAY 0.659574 (-2840 4010);
PAINT MONO (-2840 4010);
DISPLAY INVISIBLE (-2840 4010);
FORCEPROP 1 LASTPIN (-2850 4000) BN 4
J 2
(-2798 4008);
DISPLAY 0.617021 (-2798 4008);
PAINT PINK (-2798 4008);
FORCEPROP 1 LAST HDL_TAP TRUE
J 2
(-3125 3875);
DISPLAY 1.595745 (-3125 3875);
PAINT GREEN (-3125 3875);
DISPLAY INVISIBLE (-3125 3875);
FORCEPROP 1 LAST BODY_TYPE PLUMBING
J 2
(-2800 3950);
DISPLAY 1.595745 (-2800 3950);
PAINT GREEN (-2800 3950);
DISPLAY INVISIBLE (-2800 3950);
FORCEPROP 2 LAST CDS_LIB mstr_standard
J 0
(-2800 4000);
PAINT MONO (-2800 4000);
DISPLAY INVISIBLE (-2800 4000);
FORCEPROP 1 LAST PATH I161
J 2
(-2798 4000);
DISPLAY 0.872340 (-2798 4000);
PAINT GREEN (-2798 4000);
DISPLAY INVISIBLE (-2798 4000);
FORCEADD TAP..6
R 2
(-2800 4450);
FORCEPROP 3 LASTPIN (-2850 4450) SIG_NAME M_B_DQS_DP<13>
J 0
(-2840 4460);
DISPLAY 0.659574 (-2840 4460);
PAINT MONO (-2840 4460);
DISPLAY INVISIBLE (-2840 4460);
FORCEPROP 1 LASTPIN (-2850 4450) BN 13
J 2
(-2798 4458);
DISPLAY 0.617021 (-2798 4458);
PAINT PINK (-2798 4458);
FORCEPROP 1 LAST HDL_TAP TRUE
J 2
(-3125 4325);
DISPLAY 1.595745 (-3125 4325);
PAINT GREEN (-3125 4325);
DISPLAY INVISIBLE (-3125 4325);
FORCEPROP 1 LAST BODY_TYPE PLUMBING
J 2
(-2800 4400);
DISPLAY 1.595745 (-2800 4400);
PAINT GREEN (-2800 4400);
DISPLAY INVISIBLE (-2800 4400);
FORCEPROP 2 LAST CDS_LIB mstr_standard
J 0
(-2800 4450);
PAINT MONO (-2800 4450);
DISPLAY INVISIBLE (-2800 4450);
FORCEPROP 1 LAST PATH I162
J 2
(-2798 4450);
DISPLAY 0.872340 (-2798 4450);
PAINT GREEN (-2798 4450);
DISPLAY INVISIBLE (-2798 4450);
FORCEADD TAP..6
R 2
(-2800 4400);
FORCEPROP 3 LASTPIN (-2850 4400) SIG_NAME M_B_DQS_DP<12>
J 0
(-2840 4410);
DISPLAY 0.659574 (-2840 4410);
PAINT MONO (-2840 4410);
DISPLAY INVISIBLE (-2840 4410);
FORCEPROP 1 LASTPIN (-2850 4400) BN 12
J 2
(-2798 4408);
DISPLAY 0.617021 (-2798 4408);
PAINT PINK (-2798 4408);
FORCEPROP 1 LAST HDL_TAP TRUE
J 2
(-3125 4275);
DISPLAY 1.595745 (-3125 4275);
PAINT GREEN (-3125 4275);
DISPLAY INVISIBLE (-3125 4275);
FORCEPROP 1 LAST BODY_TYPE PLUMBING
J 2
(-2800 4350);
DISPLAY 1.595745 (-2800 4350);
PAINT GREEN (-2800 4350);
DISPLAY INVISIBLE (-2800 4350);
FORCEPROP 2 LAST CDS_LIB mstr_standard
J 0
(-2800 4400);
PAINT MONO (-2800 4400);
DISPLAY INVISIBLE (-2800 4400);
FORCEPROP 1 LAST PATH I163
J 2
(-2798 4400);
DISPLAY 0.872340 (-2798 4400);
PAINT GREEN (-2798 4400);
DISPLAY INVISIBLE (-2798 4400);
FORCEADD TAP..6
R 2
(-2800 4350);
FORCEPROP 3 LASTPIN (-2850 4350) SIG_NAME M_B_DQS_DP<11>
J 0
(-2840 4360);
DISPLAY 0.659574 (-2840 4360);
PAINT MONO (-2840 4360);
DISPLAY INVISIBLE (-2840 4360);
FORCEPROP 1 LASTPIN (-2850 4350) BN 11
J 2
(-2798 4358);
DISPLAY 0.617021 (-2798 4358);
PAINT PINK (-2798 4358);
FORCEPROP 1 LAST HDL_TAP TRUE
J 2
(-3125 4225);
DISPLAY 1.595745 (-3125 4225);
PAINT GREEN (-3125 4225);
DISPLAY INVISIBLE (-3125 4225);
FORCEPROP 1 LAST BODY_TYPE PLUMBING
J 2
(-2800 4300);
DISPLAY 1.595745 (-2800 4300);
PAINT GREEN (-2800 4300);
DISPLAY INVISIBLE (-2800 4300);
FORCEPROP 2 LAST CDS_LIB mstr_standard
J 0
(-2800 4350);
PAINT MONO (-2800 4350);
DISPLAY INVISIBLE (-2800 4350);
FORCEPROP 1 LAST PATH I164
J 2
(-2798 4350);
DISPLAY 0.872340 (-2798 4350);
PAINT GREEN (-2798 4350);
DISPLAY INVISIBLE (-2798 4350);
FORCEADD TAP..6
R 2
(-2800 4300);
FORCEPROP 3 LASTPIN (-2850 4300) SIG_NAME M_B_DQS_DP<10>
J 0
(-2840 4310);
DISPLAY 0.659574 (-2840 4310);
PAINT MONO (-2840 4310);
DISPLAY INVISIBLE (-2840 4310);
FORCEPROP 1 LASTPIN (-2850 4300) BN 10
J 2
(-2798 4308);
DISPLAY 0.617021 (-2798 4308);
PAINT PINK (-2798 4308);
FORCEPROP 1 LAST HDL_TAP TRUE
J 2
(-3125 4175);
DISPLAY 1.595745 (-3125 4175);
PAINT GREEN (-3125 4175);
DISPLAY INVISIBLE (-3125 4175);
FORCEPROP 1 LAST BODY_TYPE PLUMBING
J 2
(-2800 4250);
DISPLAY 1.595745 (-2800 4250);
PAINT GREEN (-2800 4250);
DISPLAY INVISIBLE (-2800 4250);
FORCEPROP 2 LAST CDS_LIB mstr_standard
J 0
(-2800 4300);
PAINT MONO (-2800 4300);
DISPLAY INVISIBLE (-2800 4300);
FORCEPROP 1 LAST PATH I165
J 2
(-2798 4300);
DISPLAY 0.872340 (-2798 4300);
PAINT GREEN (-2798 4300);
DISPLAY INVISIBLE (-2798 4300);
FORCEADD TAP..6
R 2
(-2800 4250);
FORCEPROP 3 LASTPIN (-2850 4250) SIG_NAME M_B_DQS_DP<9>
J 0
(-2840 4260);
DISPLAY 0.659574 (-2840 4260);
PAINT MONO (-2840 4260);
DISPLAY INVISIBLE (-2840 4260);
FORCEPROP 1 LASTPIN (-2850 4250) BN 9
J 2
(-2798 4258);
DISPLAY 0.617021 (-2798 4258);
PAINT PINK (-2798 4258);
FORCEPROP 1 LAST HDL_TAP TRUE
J 2
(-3125 4125);
DISPLAY 1.595745 (-3125 4125);
PAINT GREEN (-3125 4125);
DISPLAY INVISIBLE (-3125 4125);
FORCEPROP 1 LAST BODY_TYPE PLUMBING
J 2
(-2800 4200);
DISPLAY 1.595745 (-2800 4200);
PAINT GREEN (-2800 4200);
DISPLAY INVISIBLE (-2800 4200);
FORCEPROP 2 LAST CDS_LIB mstr_standard
J 0
(-2800 4250);
PAINT MONO (-2800 4250);
DISPLAY INVISIBLE (-2800 4250);
FORCEPROP 1 LAST PATH I166
J 2
(-2798 4250);
DISPLAY 0.872340 (-2798 4250);
PAINT GREEN (-2798 4250);
DISPLAY INVISIBLE (-2798 4250);
FORCEADD TAP..6
R 2
(-2800 4600);
FORCEPROP 3 LASTPIN (-2850 4600) SIG_NAME M_B_DQS_DP<16>
J 0
(-2840 4610);
DISPLAY 0.659574 (-2840 4610);
PAINT MONO (-2840 4610);
DISPLAY INVISIBLE (-2840 4610);
FORCEPROP 1 LASTPIN (-2850 4600) BN 16
J 2
(-2798 4608);
DISPLAY 0.617021 (-2798 4608);
PAINT PINK (-2798 4608);
FORCEPROP 1 LAST HDL_TAP TRUE
J 2
(-3125 4475);
DISPLAY 1.595745 (-3125 4475);
PAINT GREEN (-3125 4475);
DISPLAY INVISIBLE (-3125 4475);
FORCEPROP 1 LAST BODY_TYPE PLUMBING
J 2
(-2800 4550);
DISPLAY 1.595745 (-2800 4550);
PAINT GREEN (-2800 4550);
DISPLAY INVISIBLE (-2800 4550);
FORCEPROP 2 LAST CDS_LIB mstr_standard
J 0
(-2800 4600);
PAINT MONO (-2800 4600);
DISPLAY INVISIBLE (-2800 4600);
FORCEPROP 1 LAST PATH I167
J 2
(-2798 4600);
DISPLAY 0.872340 (-2798 4600);
PAINT GREEN (-2798 4600);
DISPLAY INVISIBLE (-2798 4600);
FORCEADD TAP..6
R 2
(-2800 4650);
FORCEPROP 3 LASTPIN (-2850 4650) SIG_NAME M_B_DQS_DP<17>
J 0
(-2840 4660);
DISPLAY 0.659574 (-2840 4660);
PAINT MONO (-2840 4660);
DISPLAY INVISIBLE (-2840 4660);
FORCEPROP 1 LASTPIN (-2850 4650) BN 17
J 2
(-2798 4658);
DISPLAY 0.617021 (-2798 4658);
PAINT PINK (-2798 4658);
FORCEPROP 1 LAST HDL_TAP TRUE
J 2
(-3125 4525);
DISPLAY 1.595745 (-3125 4525);
PAINT GREEN (-3125 4525);
DISPLAY INVISIBLE (-3125 4525);
FORCEPROP 1 LAST BODY_TYPE PLUMBING
J 2
(-2800 4600);
DISPLAY 1.595745 (-2800 4600);
PAINT GREEN (-2800 4600);
DISPLAY INVISIBLE (-2800 4600);
FORCEPROP 2 LAST CDS_LIB mstr_standard
J 2
(-2800 4650);
PAINT MONO (-2800 4650);
DISPLAY INVISIBLE (-2800 4650);
FORCEPROP 1 LAST PATH I168
J 2
(-2798 4650);
DISPLAY 0.872340 (-2798 4650);
PAINT GREEN (-2798 4650);
DISPLAY INVISIBLE (-2798 4650);
FORCEADD TAP..6
R 2
(-2800 4550);
FORCEPROP 3 LASTPIN (-2850 4550) SIG_NAME M_B_DQS_DP<15>
J 0
(-2840 4560);
DISPLAY 0.659574 (-2840 4560);
PAINT MONO (-2840 4560);
DISPLAY INVISIBLE (-2840 4560);
FORCEPROP 1 LASTPIN (-2850 4550) BN 15
J 2
(-2798 4558);
DISPLAY 0.617021 (-2798 4558);
PAINT PINK (-2798 4558);
FORCEPROP 1 LAST HDL_TAP TRUE
J 2
(-3125 4425);
DISPLAY 1.595745 (-3125 4425);
PAINT GREEN (-3125 4425);
DISPLAY INVISIBLE (-3125 4425);
FORCEPROP 1 LAST BODY_TYPE PLUMBING
J 2
(-2800 4500);
DISPLAY 1.595745 (-2800 4500);
PAINT GREEN (-2800 4500);
DISPLAY INVISIBLE (-2800 4500);
FORCEPROP 2 LAST CDS_LIB mstr_standard
J 0
(-2800 4550);
PAINT MONO (-2800 4550);
DISPLAY INVISIBLE (-2800 4550);
FORCEPROP 1 LAST PATH I169
J 2
(-2798 4550);
DISPLAY 0.872340 (-2798 4550);
PAINT GREEN (-2798 4550);
DISPLAY INVISIBLE (-2798 4550);
FORCEADD TAP..6
(-5525 1200);
FORCEPROP 3 LASTPIN (-5475 1200) SIG_NAME M_B_ECC<3>
J 0
(-5465 1210);
DISPLAY 0.659574 (-5465 1210);
PAINT MONO (-5465 1210);
DISPLAY INVISIBLE (-5465 1210);
FORCEPROP 1 LASTPIN (-5475 1200) BN 3
J 0
(-5527 1208);
DISPLAY 0.617021 (-5527 1208);
PAINT PINK (-5527 1208);
FORCEPROP 1 LAST HDL_TAP TRUE
J 0
(-5200 1075);
DISPLAY 1.595745 (-5200 1075);
PAINT GREEN (-5200 1075);
DISPLAY INVISIBLE (-5200 1075);
FORCEPROP 1 LAST BODY_TYPE PLUMBING
J 0
(-5525 1150);
DISPLAY 1.595745 (-5525 1150);
PAINT GREEN (-5525 1150);
DISPLAY INVISIBLE (-5525 1150);
FORCEPROP 2 LAST CDS_LIB mstr_standard
J 0
(-5525 1200);
PAINT MONO (-5525 1200);
DISPLAY INVISIBLE (-5525 1200);
FORCEPROP 1 LAST PATH I17
J 0
(-5527 1200);
DISPLAY 0.872340 (-5527 1200);
PAINT GREEN (-5527 1200);
DISPLAY INVISIBLE (-5527 1200);
FORCEADD TAP..6
R 2
(-2800 4500);
FORCEPROP 3 LASTPIN (-2850 4500) SIG_NAME M_B_DQS_DP<14>
J 0
(-2840 4510);
DISPLAY 0.659574 (-2840 4510);
PAINT MONO (-2840 4510);
DISPLAY INVISIBLE (-2840 4510);
FORCEPROP 1 LASTPIN (-2850 4500) BN 14
J 2
(-2798 4508);
DISPLAY 0.617021 (-2798 4508);
PAINT PINK (-2798 4508);
FORCEPROP 1 LAST HDL_TAP TRUE
J 2
(-3125 4375);
DISPLAY 1.595745 (-3125 4375);
PAINT GREEN (-3125 4375);
DISPLAY INVISIBLE (-3125 4375);
FORCEPROP 1 LAST BODY_TYPE PLUMBING
J 2
(-2800 4450);
DISPLAY 1.595745 (-2800 4450);
PAINT GREEN (-2800 4450);
DISPLAY INVISIBLE (-2800 4450);
FORCEPROP 2 LAST CDS_LIB mstr_standard
J 0
(-2800 4500);
PAINT MONO (-2800 4500);
DISPLAY INVISIBLE (-2800 4500);
FORCEPROP 1 LAST PATH I170
J 2
(-2798 4500);
DISPLAY 0.872340 (-2798 4500);
PAINT GREEN (-2798 4500);
DISPLAY INVISIBLE (-2798 4500);
FORCEADD OFFPAGE..3
(-1950 4725);
FORCEPROP 2 LAST $XR1 46 
J 0
(-1646 4725);
DISPLAY 0.638298 (-1646 4725);
PAINT MONO (-1646 4725);
FORCEPROP 2 LAST $XR0 45 
J 0
(-1736 4725);
DISPLAY 0.638298 (-1736 4725);
PAINT MONO (-1736 4725);
FORCEPROP 1 LAST COMMENT_BODY TRUE
J 0
(-2000 4625);
DISPLAY 1.170213 (-2000 4625);
PAINT GREEN (-2000 4625);
DISPLAY INVISIBLE (-2000 4625);
FORCEPROP 1 LAST OFFPAGE TRUE
J 0
(-1625 4600);
DISPLAY 1.170213 (-1625 4600);
PAINT GREEN (-1625 4600);
DISPLAY INVISIBLE (-1625 4600);
FORCEPROP 2 LAST CDS_LIB mstr_standard
J 0
(-1950 4725);
PAINT MONO (-1950 4725);
DISPLAY INVISIBLE (-1950 4725);
FORCEPROP 2 LAST PATH I171
J 0
(-1750 4800);
DISPLAY 1.021277 (-1750 4800);
PAINT ORANGE (-1750 4800);
DISPLAY INVISIBLE (-1750 4800);
FORCEADD SKX_EXT_B..4
(-4125 2550);
FORCEPROP 1 LAST LOCATION U5D1
J 0
(-4925 4900);
DISPLAY 0.617021 (-4925 4900);
PAINT AQUA (-4925 4900);
FORCEPROP 1 LAST PART_NUMBER TBD
J 0
(-4925 300);
DISPLAY 0.617021 (-4925 300);
PAINT BLUE (-4925 300);
FORCEPROP 1 LAST MATERIAL IC
J 0
(-4925 4850);
DISPLAY 0.617021 (-4925 4850);
PAINT SKYBLUE (-4925 4850);
FORCEPROP 2 LASTPIN (-3275 500) $PN K53
J 0
(-3265 510);
DISPLAY 0.617021 (-3265 510);
PAINT ORANGE (-3265 510);
FORCEPROP 2 LASTPIN (-3275 1550) $PN T47
J 0
(-3265 1560);
DISPLAY 0.617021 (-3265 1560);
PAINT ORANGE (-3265 1560);
FORCEPROP 2 LASTPIN (-3275 1500) $PN M49
J 0
(-3265 1510);
DISPLAY 0.617021 (-3265 1510);
PAINT ORANGE (-3265 1510);
FORCEPROP 2 LASTPIN (-3275 1450) $PN R48
J 0
(-3265 1460);
DISPLAY 0.617021 (-3265 1460);
PAINT ORANGE (-3265 1460);
FORCEPROP 2 LASTPIN (-3275 1400) $PN N50
J 0
(-3265 1410);
DISPLAY 0.617021 (-3265 1410);
PAINT ORANGE (-3265 1410);
FORCEPROP 2 LASTPIN (-3275 2750) $PN N48
J 0
(-3265 2760);
DISPLAY 0.617021 (-3265 2760);
PAINT ORANGE (-3265 2760);
FORCEPROP 2 LASTPIN (-3275 2700) $PN R52
J 0
(-3265 2710);
DISPLAY 0.617021 (-3265 2710);
PAINT ORANGE (-3265 2710);
FORCEPROP 2 LASTPIN (-3275 2650) $PN N52
J 0
(-3265 2660);
DISPLAY 0.617021 (-3265 2660);
PAINT ORANGE (-3265 2660);
FORCEPROP 2 LASTPIN (-3275 2600) $PN T51
J 0
(-3265 2610);
DISPLAY 0.617021 (-3265 2610);
PAINT ORANGE (-3265 2610);
FORCEPROP 2 LASTPIN (-3275 2550) $PN M51
J 0
(-3265 2560);
DISPLAY 0.617021 (-3265 2560);
PAINT ORANGE (-3265 2560);
FORCEPROP 2 LASTPIN (-3275 2500) $PN T61
J 0
(-3265 2510);
DISPLAY 0.617021 (-3265 2510);
PAINT ORANGE (-3265 2510);
FORCEPROP 2 LASTPIN (-3275 2450) $PN R60
J 0
(-3265 2460);
DISPLAY 0.617021 (-3265 2460);
PAINT ORANGE (-3265 2460);
FORCEPROP 2 LASTPIN (-3275 2400) $PN M55
J 0
(-3265 2410);
DISPLAY 0.617021 (-3265 2410);
PAINT ORANGE (-3265 2410);
FORCEPROP 2 LASTPIN (-3275 2350) $PN K59
J 0
(-3265 2360);
DISPLAY 0.617021 (-3265 2360);
PAINT ORANGE (-3265 2360);
FORCEPROP 2 LASTPIN (-3275 2300) $PN W60
J 0
(-3265 2310);
DISPLAY 0.617021 (-3265 2310);
PAINT ORANGE (-3265 2310);
FORCEPROP 2 LASTPIN (-3275 2250) $PN V61
J 0
(-3265 2260);
DISPLAY 0.617021 (-3265 2260);
PAINT ORANGE (-3265 2260);
FORCEPROP 2 LASTPIN (-3275 2200) $PN T59
J 0
(-3265 2210);
DISPLAY 0.617021 (-3265 2210);
PAINT ORANGE (-3265 2210);
FORCEPROP 2 LASTPIN (-3275 2150) $PN R58
J 0
(-3265 2160);
DISPLAY 0.617021 (-3265 2160);
PAINT ORANGE (-3265 2160);
FORCEPROP 2 LASTPIN (-3275 2100) $PN M59
J 0
(-3265 2110);
DISPLAY 0.617021 (-3265 2110);
PAINT ORANGE (-3265 2110);
FORCEPROP 2 LASTPIN (-3275 2050) $PN N58
J 0
(-3265 2060);
DISPLAY 0.617021 (-3265 2060);
PAINT ORANGE (-3265 2060);
FORCEPROP 2 LASTPIN (-3275 2000) $PN K57
J 0
(-3265 2010);
DISPLAY 0.617021 (-3265 2010);
PAINT ORANGE (-3265 2010);
FORCEPROP 2 LASTPIN (-3275 1950) $PN J58
J 0
(-3265 1960);
DISPLAY 0.617021 (-3265 1960);
PAINT ORANGE (-3265 1960);
FORCEPROP 2 LASTPIN (-3275 1900) $PN J52
J 0
(-3265 1910);
DISPLAY 0.617021 (-3265 1910);
PAINT ORANGE (-3265 1910);
FORCEPROP 2 LASTPIN (-4975 1400) $PN M67
J 2
(-4985 1410);
DISPLAY 0.617021 (-4985 1410);
PAINT ORANGE (-4985 1410);
FORCEPROP 2 LASTPIN (-4975 1350) $PN H67
J 2
(-4985 1360);
DISPLAY 0.617021 (-4985 1360);
PAINT ORANGE (-4985 1360);
FORCEPROP 2 LASTPIN (-4975 1300) $PN M69
J 2
(-4985 1310);
DISPLAY 0.617021 (-4985 1310);
PAINT ORANGE (-4985 1310);
FORCEPROP 2 LASTPIN (-4975 1250) $PN L70
J 2
(-4985 1260);
DISPLAY 0.617021 (-4985 1260);
PAINT ORANGE (-4985 1260);
FORCEPROP 2 LASTPIN (-4975 1200) $PN L66
J 2
(-4985 1210);
DISPLAY 0.617021 (-4985 1210);
PAINT ORANGE (-4985 1210);
FORCEPROP 2 LASTPIN (-4975 1150) $PN J66
J 2
(-4985 1160);
DISPLAY 0.617021 (-4985 1160);
PAINT ORANGE (-4985 1160);
FORCEPROP 2 LASTPIN (-4975 1050) $PN J70
J 2
(-4985 1060);
DISPLAY 0.617021 (-4985 1060);
PAINT ORANGE (-4985 1060);
FORCEPROP 2 LASTPIN (-3275 4650) $PN J68
J 0
(-3265 4660);
DISPLAY 0.617021 (-3265 4660);
PAINT ORANGE (-3265 4660);
FORCEPROP 2 LASTPIN (-3275 4600) $PN V27
J 0
(-3265 4610);
DISPLAY 0.617021 (-3265 4610);
PAINT ORANGE (-3265 4610);
FORCEPROP 2 LASTPIN (-3275 4550) $PN C28
J 0
(-3265 4560);
DISPLAY 0.617021 (-3265 4560);
PAINT ORANGE (-3265 4560);
FORCEPROP 2 LASTPIN (-3275 4500) $PN C34
J 0
(-3265 4510);
DISPLAY 0.617021 (-3265 4510);
PAINT ORANGE (-3265 4510);
FORCEPROP 2 LASTPIN (-3275 4450) $PN L42
J 0
(-3265 4460);
DISPLAY 0.617021 (-3265 4460);
PAINT ORANGE (-3265 4460);
FORCEPROP 2 LASTPIN (-3275 4400) $PN D73
J 0
(-3265 4410);
DISPLAY 0.617021 (-3265 4410);
PAINT ORANGE (-3265 4410);
FORCEPROP 2 LASTPIN (-3275 4350) $PN F79
J 0
(-3265 4360);
DISPLAY 0.617021 (-3265 4360);
PAINT ORANGE (-3265 4360);
FORCEPROP 2 LASTPIN (-3275 4300) $PN AF81
J 0
(-3265 4310);
DISPLAY 0.617021 (-3265 4310);
PAINT ORANGE (-3265 4310);
FORCEPROP 2 LASTPIN (-3275 4250) $PN AT81
J 0
(-3265 4260);
DISPLAY 0.617021 (-3265 4260);
PAINT ORANGE (-3265 4260);
FORCEPROP 2 LASTPIN (-3275 4200) $PN L68
J 0
(-3265 4210);
DISPLAY 0.617021 (-3265 4210);
PAINT ORANGE (-3265 4210);
FORCEPROP 2 LASTPIN (-3275 4150) $PN Y27
J 0
(-3265 4160);
DISPLAY 0.617021 (-3265 4160);
PAINT ORANGE (-3265 4160);
FORCEPROP 2 LASTPIN (-3275 4100) $PN E28
J 0
(-3265 4110);
DISPLAY 0.617021 (-3265 4110);
PAINT ORANGE (-3265 4110);
FORCEPROP 2 LASTPIN (-3275 4050) $PN E34
J 0
(-3265 4060);
DISPLAY 0.617021 (-3265 4060);
PAINT ORANGE (-3265 4060);
FORCEPROP 2 LASTPIN (-3275 4000) $PN R42
J 0
(-3265 4010);
DISPLAY 0.617021 (-3265 4010);
PAINT ORANGE (-3265 4010);
FORCEPROP 2 LASTPIN (-3275 3950) $PN F73
J 0
(-3265 3960);
DISPLAY 0.617021 (-3265 3960);
PAINT ORANGE (-3265 3960);
FORCEPROP 2 LASTPIN (-3275 3900) $PN H79
J 0
(-3265 3910);
DISPLAY 0.617021 (-3265 3910);
PAINT ORANGE (-3265 3910);
FORCEPROP 2 LASTPIN (-3275 3850) $PN AE80
J 0
(-3265 3860);
DISPLAY 0.617021 (-3265 3860);
PAINT ORANGE (-3265 3860);
FORCEPROP 2 LASTPIN (-3275 3800) $PN AR80
J 0
(-3265 3810);
DISPLAY 0.617021 (-3265 3810);
PAINT ORANGE (-3265 3810);
FORCEPROP 2 LASTPIN (-3275 3700) $PN G68
J 0
(-3265 3710);
DISPLAY 0.617021 (-3265 3710);
PAINT ORANGE (-3265 3710);
FORCEPROP 2 LASTPIN (-3275 3650) $PN T27
J 0
(-3265 3660);
DISPLAY 0.617021 (-3265 3660);
PAINT ORANGE (-3265 3660);
FORCEPROP 2 LASTPIN (-3275 3600) $PN A28
J 0
(-3265 3610);
DISPLAY 0.617021 (-3265 3610);
PAINT ORANGE (-3265 3610);
FORCEPROP 2 LASTPIN (-3275 3550) $PN A34
J 0
(-3265 3560);
DISPLAY 0.617021 (-3265 3560);
PAINT ORANGE (-3265 3560);
FORCEPROP 2 LASTPIN (-3275 3500) $PN J42
J 0
(-3265 3510);
DISPLAY 0.617021 (-3265 3510);
PAINT ORANGE (-3265 3510);
FORCEPROP 2 LASTPIN (-3275 3450) $PN B73
J 0
(-3265 3460);
DISPLAY 0.617021 (-3265 3460);
PAINT ORANGE (-3265 3460);
FORCEPROP 2 LASTPIN (-3275 3400) $PN D79
J 0
(-3265 3410);
DISPLAY 0.617021 (-3265 3410);
PAINT ORANGE (-3265 3410);
FORCEPROP 2 LASTPIN (-3275 3350) $PN AG82
J 0
(-3265 3360);
DISPLAY 0.617021 (-3265 3360);
PAINT ORANGE (-3265 3360);
FORCEPROP 2 LASTPIN (-3275 3300) $PN AU82
J 0
(-3265 3310);
DISPLAY 0.617021 (-3265 3310);
PAINT ORANGE (-3265 3310);
FORCEPROP 2 LASTPIN (-3275 3250) $PN N68
J 0
(-3265 3260);
DISPLAY 0.617021 (-3265 3260);
PAINT ORANGE (-3265 3260);
FORCEPROP 2 LASTPIN (-3275 3200) $PN AB27
J 0
(-3265 3210);
DISPLAY 0.617021 (-3265 3210);
PAINT ORANGE (-3265 3210);
FORCEPROP 2 LASTPIN (-3275 3150) $PN G28
J 0
(-3265 3160);
DISPLAY 0.617021 (-3265 3160);
PAINT ORANGE (-3265 3160);
FORCEPROP 2 LASTPIN (-3275 3100) $PN G34
J 0
(-3265 3110);
DISPLAY 0.617021 (-3265 3110);
PAINT ORANGE (-3265 3110);
FORCEPROP 2 LASTPIN (-3275 3050) $PN N42
J 0
(-3265 3060);
DISPLAY 0.617021 (-3265 3060);
PAINT ORANGE (-3265 3060);
FORCEPROP 2 LASTPIN (-3275 3000) $PN H73
J 0
(-3265 3010);
DISPLAY 0.617021 (-3265 3010);
PAINT ORANGE (-3265 3010);
FORCEPROP 2 LASTPIN (-3275 2950) $PN K79
J 0
(-3265 2960);
DISPLAY 0.617021 (-3265 2960);
PAINT ORANGE (-3265 2960);
FORCEPROP 2 LASTPIN (-3275 2900) $PN AD79
J 0
(-3265 2910);
DISPLAY 0.617021 (-3265 2910);
PAINT ORANGE (-3265 2910);
FORCEPROP 2 LASTPIN (-3275 2850) $PN AP79
J 0
(-3265 2860);
DISPLAY 0.617021 (-3265 2860);
PAINT ORANGE (-3265 2860);
FORCEPROP 2 LASTPIN (-4975 4650) $PN AA26
J 2
(-4985 4660);
DISPLAY 0.617021 (-4985 4660);
PAINT ORANGE (-4985 4660);
FORCEPROP 2 LASTPIN (-4975 4600) $PN U26
J 2
(-4985 4610);
DISPLAY 0.617021 (-4985 4610);
PAINT ORANGE (-4985 4610);
FORCEPROP 2 LASTPIN (-4975 4550) $PN Y29
J 2
(-4985 4560);
DISPLAY 0.617021 (-4985 4560);
PAINT ORANGE (-4985 4560);
FORCEPROP 2 LASTPIN (-4975 4500) $PN V29
J 2
(-4985 4510);
DISPLAY 0.617021 (-4985 4510);
PAINT ORANGE (-4985 4510);
FORCEPROP 2 LASTPIN (-4975 4450) $PN Y25
J 2
(-4985 4460);
DISPLAY 0.617021 (-4985 4460);
PAINT ORANGE (-4985 4460);
FORCEPROP 2 LASTPIN (-4975 4400) $PN V25
J 2
(-4985 4410);
DISPLAY 0.617021 (-4985 4410);
PAINT ORANGE (-4985 4410);
FORCEPROP 2 LASTPIN (-4975 4350) $PN AA28
J 2
(-4985 4360);
DISPLAY 0.617021 (-4985 4360);
PAINT ORANGE (-4985 4360);
FORCEPROP 2 LASTPIN (-4975 4300) $PN U28
J 2
(-4985 4310);
DISPLAY 0.617021 (-4985 4310);
PAINT ORANGE (-4985 4310);
FORCEPROP 2 LASTPIN (-4975 4250) $PN F27
J 2
(-4985 4260);
DISPLAY 0.617021 (-4985 4260);
PAINT ORANGE (-4985 4260);
FORCEPROP 2 LASTPIN (-4975 4200) $PN B27
J 2
(-4985 4210);
DISPLAY 0.617021 (-4985 4210);
PAINT ORANGE (-4985 4210);
FORCEPROP 2 LASTPIN (-4975 4150) $PN F29
J 2
(-4985 4160);
DISPLAY 0.617021 (-4985 4160);
PAINT ORANGE (-4985 4160);
FORCEPROP 2 LASTPIN (-4975 4100) $PN E30
J 2
(-4985 4110);
DISPLAY 0.617021 (-4985 4110);
PAINT ORANGE (-4985 4110);
FORCEPROP 2 LASTPIN (-4975 4050) $PN E26
J 2
(-4985 4060);
DISPLAY 0.617021 (-4985 4060);
PAINT ORANGE (-4985 4060);
FORCEPROP 2 LASTPIN (-4975 4000) $PN C26
J 2
(-4985 4010);
DISPLAY 0.617021 (-4985 4010);
PAINT ORANGE (-4985 4010);
FORCEPROP 2 LASTPIN (-4975 3950) $PN B29
J 2
(-4985 3960);
DISPLAY 0.617021 (-4985 3960);
PAINT ORANGE (-4985 3960);
FORCEPROP 2 LASTPIN (-4975 3850) $PN F33
J 2
(-4985 3860);
DISPLAY 0.617021 (-4985 3860);
PAINT ORANGE (-4985 3860);
FORCEPROP 2 LASTPIN (-4975 3800) $PN B33
J 2
(-4985 3810);
DISPLAY 0.617021 (-4985 3810);
PAINT ORANGE (-4985 3810);
FORCEPROP 2 LASTPIN (-4975 3750) $PN F35
J 2
(-4985 3760);
DISPLAY 0.617021 (-4985 3760);
PAINT ORANGE (-4985 3760);
FORCEPROP 2 LASTPIN (-4975 3700) $PN E36
J 2
(-4985 3710);
DISPLAY 0.617021 (-4985 3710);
PAINT ORANGE (-4985 3710);
FORCEPROP 2 LASTPIN (-4975 3650) $PN E32
J 2
(-4985 3660);
DISPLAY 0.617021 (-4985 3660);
PAINT ORANGE (-4985 3660);
FORCEPROP 2 LASTPIN (-4975 3600) $PN C32
J 2
(-4985 3610);
DISPLAY 0.617021 (-4985 3610);
PAINT ORANGE (-4985 3610);
FORCEPROP 2 LASTPIN (-4975 3550) $PN B35
J 2
(-4985 3560);
DISPLAY 0.617021 (-4985 3560);
PAINT ORANGE (-4985 3560);
FORCEPROP 2 LASTPIN (-4975 3500) $PN C36
J 2
(-4985 3510);
DISPLAY 0.617021 (-4985 3510);
PAINT ORANGE (-4985 3510);
FORCEPROP 2 LASTPIN (-4975 3450) $PN P41
J 2
(-4985 3460);
DISPLAY 0.617021 (-4985 3460);
PAINT ORANGE (-4985 3460);
FORCEPROP 2 LASTPIN (-4975 3400) $PN K41
J 2
(-4985 3410);
DISPLAY 0.617021 (-4985 3410);
PAINT ORANGE (-4985 3410);
FORCEPROP 2 LASTPIN (-4975 3350) $PN T43
J 2
(-4985 3360);
DISPLAY 0.617021 (-4985 3360);
PAINT ORANGE (-4985 3360);
FORCEPROP 2 LASTPIN (-4975 3300) $PN P43
J 2
(-4985 3310);
DISPLAY 0.617021 (-4985 3310);
PAINT ORANGE (-4985 3310);
FORCEPROP 2 LASTPIN (-4975 3250) $PN N40
J 2
(-4985 3260);
DISPLAY 0.617021 (-4985 3260);
PAINT ORANGE (-4985 3260);
FORCEPROP 2 LASTPIN (-4975 3200) $PN L40
J 2
(-4985 3210);
DISPLAY 0.617021 (-4985 3210);
PAINT ORANGE (-4985 3210);
FORCEPROP 2 LASTPIN (-4975 3150) $PN H43
J 2
(-4985 3160);
DISPLAY 0.617021 (-4985 3160);
PAINT ORANGE (-4985 3160);
FORCEPROP 2 LASTPIN (-4975 3050) $PN G72
J 2
(-4985 3060);
DISPLAY 0.617021 (-4985 3060);
PAINT ORANGE (-4985 3060);
FORCEPROP 2 LASTPIN (-4975 2950) $PN G74
J 2
(-4985 2960);
DISPLAY 0.617021 (-4985 2960);
PAINT ORANGE (-4985 2960);
FORCEPROP 2 LASTPIN (-4975 2900) $PN F75
J 2
(-4985 2910);
DISPLAY 0.617021 (-4985 2910);
PAINT ORANGE (-4985 2910);
FORCEPROP 2 LASTPIN (-4975 2850) $PN F71
J 2
(-4985 2860);
DISPLAY 0.617021 (-4985 2860);
PAINT ORANGE (-4985 2860);
FORCEPROP 2 LASTPIN (-4975 2800) $PN D71
J 2
(-4985 2810);
DISPLAY 0.617021 (-4985 2810);
PAINT ORANGE (-4985 2810);
FORCEPROP 2 LASTPIN (-4975 2750) $PN C74
J 2
(-4985 2760);
DISPLAY 0.617021 (-4985 2760);
PAINT ORANGE (-4985 2760);
FORCEPROP 2 LASTPIN (-4975 2700) $PN D75
J 2
(-4985 2710);
DISPLAY 0.617021 (-4985 2710);
PAINT ORANGE (-4985 2710);
FORCEPROP 2 LASTPIN (-4975 2650) $PN J78
J 2
(-4985 2660);
DISPLAY 0.617021 (-4985 2660);
PAINT ORANGE (-4985 2660);
FORCEPROP 2 LASTPIN (-4975 2600) $PN E78
J 2
(-4985 2610);
DISPLAY 0.617021 (-4985 2610);
PAINT ORANGE (-4985 2610);
FORCEPROP 2 LASTPIN (-4975 2550) $PN H81
J 2
(-4985 2560);
DISPLAY 0.617021 (-4985 2560);
PAINT ORANGE (-4985 2560);
FORCEPROP 2 LASTPIN (-4975 2500) $PN F81
J 2
(-4985 2510);
DISPLAY 0.617021 (-4985 2510);
PAINT ORANGE (-4985 2510);
FORCEPROP 2 LASTPIN (-4975 2450) $PN H77
J 2
(-4985 2460);
DISPLAY 0.617021 (-4985 2460);
PAINT ORANGE (-4985 2460);
FORCEPROP 2 LASTPIN (-4975 2400) $PN F77
J 2
(-4985 2410);
DISPLAY 0.617021 (-4985 2410);
PAINT ORANGE (-4985 2410);
FORCEPROP 2 LASTPIN (-4975 2350) $PN J80
J 2
(-4985 2360);
DISPLAY 0.617021 (-4985 2360);
PAINT ORANGE (-4985 2360);
FORCEPROP 2 LASTPIN (-4975 2300) $PN E80
J 2
(-4985 2310);
DISPLAY 0.617021 (-4985 2310);
PAINT ORANGE (-4985 2310);
FORCEPROP 2 LASTPIN (-4975 2250) $PN AC80
J 2
(-4985 2260);
DISPLAY 0.617021 (-4985 2260);
PAINT ORANGE (-4985 2260);
FORCEPROP 2 LASTPIN (-4975 2200) $PN AE82
J 2
(-4985 2210);
DISPLAY 0.617021 (-4985 2210);
PAINT ORANGE (-4985 2210);
FORCEPROP 2 LASTPIN (-4975 2150) $PN AH79
J 2
(-4985 2160);
DISPLAY 0.617021 (-4985 2160);
PAINT ORANGE (-4985 2160);
FORCEPROP 2 LASTPIN (-4975 2100) $PN AJ80
J 2
(-4985 2110);
DISPLAY 0.617021 (-4985 2110);
PAINT ORANGE (-4985 2110);
FORCEPROP 2 LASTPIN (-4975 2050) $PN AB81
J 2
(-4985 2060);
DISPLAY 0.617021 (-4985 2060);
PAINT ORANGE (-4985 2060);
FORCEPROP 2 LASTPIN (-4975 2000) $PN AC82
J 2
(-4985 2010);
DISPLAY 0.617021 (-4985 2010);
PAINT ORANGE (-4985 2010);
FORCEPROP 2 LASTPIN (-4975 1950) $PN AF79
J 2
(-4985 1960);
DISPLAY 0.617021 (-4985 1960);
PAINT ORANGE (-4985 1960);
FORCEPROP 2 LASTPIN (-4975 1900) $PN AH81
J 2
(-4985 1910);
DISPLAY 0.617021 (-4985 1910);
PAINT ORANGE (-4985 1910);
FORCEPROP 2 LASTPIN (-4975 1850) $PN AN80
J 2
(-4985 1860);
DISPLAY 0.617021 (-4985 1860);
PAINT ORANGE (-4985 1860);
FORCEPROP 2 LASTPIN (-4975 1800) $PN AR82
J 2
(-4985 1810);
DISPLAY 0.617021 (-4985 1810);
PAINT ORANGE (-4985 1810);
FORCEPROP 2 LASTPIN (-4975 1750) $PN AV79
J 2
(-4985 1760);
DISPLAY 0.617021 (-4985 1760);
PAINT ORANGE (-4985 1760);
FORCEPROP 2 LASTPIN (-4975 1700) $PN AW80
J 2
(-4985 1710);
DISPLAY 0.617021 (-4985 1710);
PAINT ORANGE (-4985 1710);
FORCEPROP 2 LASTPIN (-4975 1650) $PN AM81
J 2
(-4985 1660);
DISPLAY 0.617021 (-4985 1660);
PAINT ORANGE (-4985 1660);
FORCEPROP 2 LASTPIN (-4975 1600) $PN AN82
J 2
(-4985 1610);
DISPLAY 0.617021 (-4985 1610);
PAINT ORANGE (-4985 1610);
FORCEPROP 2 LASTPIN (-4975 1550) $PN AT79
J 2
(-4985 1560);
DISPLAY 0.617021 (-4985 1560);
PAINT ORANGE (-4985 1560);
FORCEPROP 2 LASTPIN (-4975 1500) $PN AV81
J 2
(-4985 1510);
DISPLAY 0.617021 (-4985 1510);
PAINT ORANGE (-4985 1510);
FORCEPROP 2 LASTPIN (-3275 1300) $PN R46
J 0
(-3265 1310);
DISPLAY 0.617021 (-3265 1310);
PAINT ORANGE (-3265 1310);
FORCEPROP 2 LASTPIN (-3275 1250) $PN M45
J 0
(-3265 1260);
DISPLAY 0.617021 (-3265 1260);
PAINT ORANGE (-3265 1260);
FORCEPROP 2 LASTPIN (-3275 1200) $PN T49
J 0
(-3265 1210);
DISPLAY 0.617021 (-3265 1210);
PAINT ORANGE (-3265 1210);
FORCEPROP 2 LASTPIN (-3275 1150) $PN J50
J 0
(-3265 1160);
DISPLAY 0.617021 (-3265 1160);
PAINT ORANGE (-3265 1160);
FORCEPROP 2 LASTPIN (-3275 1100) $PN V47
J 0
(-3265 1110);
DISPLAY 0.617021 (-3265 1110);
PAINT ORANGE (-3265 1110);
FORCEPROP 2 LASTPIN (-3275 1050) $PN N46
J 0
(-3265 1060);
DISPLAY 0.617021 (-3265 1060);
PAINT ORANGE (-3265 1060);
FORCEPROP 2 LASTPIN (-3275 1000) $PN R50
J 0
(-3265 1010);
DISPLAY 0.617021 (-3265 1010);
PAINT ORANGE (-3265 1010);
FORCEPROP 2 LASTPIN (-3275 950) $PN K51
J 0
(-3265 960);
DISPLAY 0.617021 (-3265 960);
PAINT ORANGE (-3265 960);
FORCEPROP 2 LASTPIN (-4975 950) $PN T57
J 2
(-4985 960);
DISPLAY 0.617021 (-4985 960);
PAINT ORANGE (-4985 960);
FORCEPROP 2 LASTPIN (-4975 900) $PN M57
J 2
(-4985 910);
DISPLAY 0.617021 (-4985 910);
PAINT ORANGE (-4985 910);
FORCEPROP 2 LASTPIN (-4975 850) $PN T55
J 2
(-4985 860);
DISPLAY 0.617021 (-4985 860);
PAINT ORANGE (-4985 860);
FORCEPROP 2 LASTPIN (-4975 800) $PN N54
J 2
(-4985 810);
DISPLAY 0.617021 (-4985 810);
PAINT ORANGE (-4985 810);
FORCEPROP 2 LASTPIN (-4975 750) $PN R56
J 2
(-4985 760);
DISPLAY 0.617021 (-4985 760);
PAINT ORANGE (-4985 760);
FORCEPROP 2 LASTPIN (-4975 700) $PN N56
J 2
(-4985 710);
DISPLAY 0.617021 (-4985 710);
PAINT ORANGE (-4985 710);
FORCEPROP 2 LASTPIN (-4975 650) $PN R54
J 2
(-4985 660);
DISPLAY 0.617021 (-4985 660);
PAINT ORANGE (-4985 660);
FORCEPROP 2 LASTPIN (-4975 600) $PN M53
J 2
(-4985 610);
DISPLAY 0.617021 (-4985 610);
PAINT ORANGE (-4985 610);
FORCEPROP 2 LASTPIN (-3275 1800) $PN L64
J 0
(-3265 1810);
DISPLAY 0.617021 (-3265 1810);
PAINT ORANGE (-3265 1810);
FORCEPROP 2 LASTPIN (-3275 1750) $PN K63
J 0
(-3265 1760);
DISPLAY 0.617021 (-3265 1760);
PAINT ORANGE (-3265 1760);
FORCEPROP 2 LASTPIN (-3275 1700) $PN R64
J 0
(-3265 1710);
DISPLAY 0.617021 (-3265 1710);
PAINT ORANGE (-3265 1710);
FORCEPROP 2 LASTPIN (-3275 1650) $PN N62
J 0
(-3265 1660);
DISPLAY 0.617021 (-3265 1660);
PAINT ORANGE (-3265 1660);
FORCEPROP 2 LASTPIN (-4975 500) $PN M47
J 2
(-4985 510);
DISPLAY 0.617021 (-4985 510);
PAINT ORANGE (-4985 510);
FORCEPROP 2 LASTPIN (-3275 850) $PN N60
J 0
(-3265 860);
DISPLAY 0.617021 (-3265 860);
PAINT ORANGE (-3265 860);
FORCEPROP 2 LASTPIN (-3275 800) $PN M61
J 0
(-3265 810);
DISPLAY 0.617021 (-3265 810);
PAINT ORANGE (-3265 810);
FORCEPROP 2 LASTPIN (-3275 750) $PN K55
J 0
(-3265 760);
DISPLAY 0.617021 (-3265 760);
PAINT ORANGE (-3265 760);
FORCEPROP 2 LASTPIN (-3275 700) $PN T53
J 0
(-3265 710);
DISPLAY 0.617021 (-3265 710);
PAINT ORANGE (-3265 710);
FORCEPROP 2 LASTPIN (-3275 550) $PN W62
J 0
(-3265 560);
DISPLAY 0.617021 (-3265 560);
PAINT ORANGE (-3265 560);
FORCEPROP 2 LASTPIN (-3275 600) $PN T63
J 0
(-3265 610);
DISPLAY 0.617021 (-3265 610);
PAINT ORANGE (-3265 610);
FORCEPROP 2 LASTPIN (-4975 3100) $PN K43
J 2
(-4985 3110);
DISPLAY 0.617021 (-4985 3110);
PAINT ORANGE (-4985 3110);
FORCEPROP 2 LASTPIN (-4975 3000) $PN C72
J 2
(-4985 3010);
DISPLAY 0.617021 (-4985 3010);
PAINT ORANGE (-4985 3010);
FORCEPROP 2 LASTPIN (-4975 1100) $PN H69
J 2
(-4985 1110);
DISPLAY 0.617021 (-4985 1110);
PAINT ORANGE (-4985 1110);
FORCEPROP 2 LASTPIN (-4975 3900) $PN C30
J 2
(-4985 3910);
DISPLAY 0.617021 (-4985 3910);
PAINT ORANGE (-4985 3910);
FORCEPROP 1 LAST PACK_TYPE BGA1
J 0
(-4925 4950);
PAINT SKYBLUE (-4925 4950);
DISPLAY INVISIBLE (-4925 4950);
FORCEPROP 2 LAST SEC_TYPE BGA1
J 0
(-4925 4950);
DISPLAY 1.021277 (-4925 4950);
PAINT ORANGE (-4925 4950);
DISPLAY INVISIBLE (-4925 4950);
FORCEPROP 2 LAST CDS_LIB chpset_lib
J 0
(-4125 2550);
PAINT ORANGE (-4125 2550);
DISPLAY INVISIBLE (-4125 2550);
FORCEPROP 2 LAST SEC 4
J 0
(-4925 4950);
DISPLAY 0.680851 (-4925 4950);
PAINT MONO (-4925 4950);
DISPLAY INVISIBLE (-4925 4950);
FORCEPROP 2 LAST CDS_LOCATION U5D1
J 0
(-4925 4900);
DISPLAY 0.617021 (-4925 4900);
PAINT AQUA (-4925 4900);
DISPLAY INVISIBLE (-4925 4900);
FORCEPROP 1 LAST PATH I172
J 0
(-4125 4850);
PAINT GREEN (-4125 4850);
DISPLAY INVISIBLE (-4125 4850);
FORCEPROP 0 LAST ROOM CPU0
J 0
(-4925 5000);
DISPLAY 1.021277 (-4925 5000);
PAINT ORANGE (-4925 5000);
DISPLAY INVISIBLE (-4925 5000);
FORCEADD TAP..6
(-5525 1300);
FORCEPROP 3 LASTPIN (-5475 1300) SIG_NAME M_B_ECC<5>
J 0
(-5465 1310);
DISPLAY 0.659574 (-5465 1310);
PAINT MONO (-5465 1310);
DISPLAY INVISIBLE (-5465 1310);
FORCEPROP 1 LASTPIN (-5475 1300) BN 5
J 0
(-5527 1308);
DISPLAY 0.617021 (-5527 1308);
PAINT PINK (-5527 1308);
FORCEPROP 1 LAST HDL_TAP TRUE
J 0
(-5200 1175);
DISPLAY 1.595745 (-5200 1175);
PAINT GREEN (-5200 1175);
DISPLAY INVISIBLE (-5200 1175);
FORCEPROP 1 LAST BODY_TYPE PLUMBING
J 0
(-5525 1250);
DISPLAY 1.595745 (-5525 1250);
PAINT GREEN (-5525 1250);
DISPLAY INVISIBLE (-5525 1250);
FORCEPROP 2 LAST CDS_LIB mstr_standard
J 0
(-5525 1300);
PAINT MONO (-5525 1300);
DISPLAY INVISIBLE (-5525 1300);
FORCEPROP 1 LAST PATH I18
J 0
(-5527 1300);
DISPLAY 0.872340 (-5527 1300);
PAINT GREEN (-5527 1300);
DISPLAY INVISIBLE (-5527 1300);
FORCEADD TAP..6
(-5525 1350);
FORCEPROP 3 LASTPIN (-5475 1350) SIG_NAME M_B_ECC<6>
J 0
(-5465 1360);
DISPLAY 0.659574 (-5465 1360);
PAINT MONO (-5465 1360);
DISPLAY INVISIBLE (-5465 1360);
FORCEPROP 1 LASTPIN (-5475 1350) BN 6
J 0
(-5527 1358);
DISPLAY 0.617021 (-5527 1358);
PAINT PINK (-5527 1358);
FORCEPROP 1 LAST HDL_TAP TRUE
J 0
(-5200 1225);
DISPLAY 1.595745 (-5200 1225);
PAINT GREEN (-5200 1225);
DISPLAY INVISIBLE (-5200 1225);
FORCEPROP 1 LAST BODY_TYPE PLUMBING
J 0
(-5525 1300);
DISPLAY 1.595745 (-5525 1300);
PAINT GREEN (-5525 1300);
DISPLAY INVISIBLE (-5525 1300);
FORCEPROP 2 LAST CDS_LIB mstr_standard
J 0
(-5525 1350);
PAINT MONO (-5525 1350);
DISPLAY INVISIBLE (-5525 1350);
FORCEPROP 1 LAST PATH I19
J 0
(-5527 1350);
DISPLAY 0.872340 (-5527 1350);
PAINT GREEN (-5527 1350);
DISPLAY INVISIBLE (-5527 1350);
FORCEADD OFFPAGE..5
(-6375 800);
FORCEPROP 2 LAST $XR1 46 
J 0
(-6719 800);
DISPLAY 0.638298 (-6719 800);
PAINT MONO (-6719 800);
FORCEPROP 2 LAST $XR0 45 
J 0
(-6629 800);
DISPLAY 0.638298 (-6629 800);
PAINT MONO (-6629 800);
FORCEPROP 1 LAST COMMENT_BODY TRUE
J 0
(-6275 725);
DISPLAY 1.170213 (-6275 725);
PAINT GREEN (-6275 725);
DISPLAY INVISIBLE (-6275 725);
FORCEPROP 1 LAST OFFPAGE TRUE
J 0
(-6050 675);
DISPLAY 1.170213 (-6050 675);
PAINT GREEN (-6050 675);
DISPLAY INVISIBLE (-6050 675);
FORCEPROP 2 LAST CDS_LIB mstr_standard
J 0
(-6375 800);
PAINT MONO (-6375 800);
DISPLAY INVISIBLE (-6375 800);
FORCEPROP 2 LAST PATH I2
J 0
(-6325 875);
DISPLAY 1.021277 (-6325 875);
PAINT ORANGE (-6325 875);
DISPLAY INVISIBLE (-6325 875);
FORCEADD TAP..6
(-5525 1400);
FORCEPROP 3 LASTPIN (-5475 1400) SIG_NAME M_B_ECC<7>
J 0
(-5465 1410);
DISPLAY 0.659574 (-5465 1410);
PAINT MONO (-5465 1410);
DISPLAY INVISIBLE (-5465 1410);
FORCEPROP 1 LASTPIN (-5475 1400) BN 7
J 0
(-5527 1408);
DISPLAY 0.617021 (-5527 1408);
PAINT PINK (-5527 1408);
FORCEPROP 1 LAST HDL_TAP TRUE
J 0
(-5200 1275);
DISPLAY 1.595745 (-5200 1275);
PAINT GREEN (-5200 1275);
DISPLAY INVISIBLE (-5200 1275);
FORCEPROP 1 LAST BODY_TYPE PLUMBING
J 0
(-5525 1350);
DISPLAY 1.595745 (-5525 1350);
PAINT GREEN (-5525 1350);
DISPLAY INVISIBLE (-5525 1350);
FORCEPROP 2 LAST CDS_LIB mstr_standard
J 0
(-5525 1400);
PAINT MONO (-5525 1400);
DISPLAY INVISIBLE (-5525 1400);
FORCEPROP 1 LAST PATH I20
J 0
(-5527 1400);
DISPLAY 0.872340 (-5527 1400);
PAINT GREEN (-5527 1400);
DISPLAY INVISIBLE (-5527 1400);
FORCEADD TAP..6
(-5525 1500);
FORCEPROP 3 LASTPIN (-5475 1500) SIG_NAME M_B_DQ<0>
J 0
(-5465 1510);
DISPLAY 0.659574 (-5465 1510);
PAINT MONO (-5465 1510);
DISPLAY INVISIBLE (-5465 1510);
FORCEPROP 1 LASTPIN (-5475 1500) BN 0
J 0
(-5527 1508);
DISPLAY 0.617021 (-5527 1508);
PAINT PINK (-5527 1508);
FORCEPROP 1 LAST HDL_TAP TRUE
J 0
(-5200 1375);
DISPLAY 1.595745 (-5200 1375);
PAINT GREEN (-5200 1375);
DISPLAY INVISIBLE (-5200 1375);
FORCEPROP 1 LAST BODY_TYPE PLUMBING
J 0
(-5525 1450);
DISPLAY 1.595745 (-5525 1450);
PAINT GREEN (-5525 1450);
DISPLAY INVISIBLE (-5525 1450);
FORCEPROP 2 LAST CDS_LIB mstr_standard
J 0
(-5525 1500);
PAINT MONO (-5525 1500);
DISPLAY INVISIBLE (-5525 1500);
FORCEPROP 1 LAST PATH I21
J 0
(-5527 1500);
DISPLAY 0.872340 (-5527 1500);
PAINT GREEN (-5527 1500);
DISPLAY INVISIBLE (-5527 1500);
FORCEADD TAP..6
(-5525 1550);
FORCEPROP 3 LASTPIN (-5475 1550) SIG_NAME M_B_DQ<1>
J 0
(-5465 1560);
DISPLAY 0.659574 (-5465 1560);
PAINT MONO (-5465 1560);
DISPLAY INVISIBLE (-5465 1560);
FORCEPROP 1 LASTPIN (-5475 1550) BN 1
J 0
(-5527 1558);
DISPLAY 0.617021 (-5527 1558);
PAINT PINK (-5527 1558);
FORCEPROP 1 LAST HDL_TAP TRUE
J 0
(-5200 1425);
DISPLAY 1.595745 (-5200 1425);
PAINT GREEN (-5200 1425);
DISPLAY INVISIBLE (-5200 1425);
FORCEPROP 1 LAST BODY_TYPE PLUMBING
J 0
(-5525 1500);
DISPLAY 1.595745 (-5525 1500);
PAINT GREEN (-5525 1500);
DISPLAY INVISIBLE (-5525 1500);
FORCEPROP 2 LAST CDS_LIB mstr_standard
J 0
(-5525 1550);
PAINT MONO (-5525 1550);
DISPLAY INVISIBLE (-5525 1550);
FORCEPROP 1 LAST PATH I22
J 0
(-5527 1550);
DISPLAY 0.872340 (-5527 1550);
PAINT GREEN (-5527 1550);
DISPLAY INVISIBLE (-5527 1550);
FORCEADD TAP..6
(-5525 1600);
FORCEPROP 3 LASTPIN (-5475 1600) SIG_NAME M_B_DQ<2>
J 0
(-5465 1610);
DISPLAY 0.659574 (-5465 1610);
PAINT MONO (-5465 1610);
DISPLAY INVISIBLE (-5465 1610);
FORCEPROP 1 LASTPIN (-5475 1600) BN 2
J 0
(-5527 1608);
DISPLAY 0.617021 (-5527 1608);
PAINT PINK (-5527 1608);
FORCEPROP 1 LAST HDL_TAP TRUE
J 0
(-5200 1475);
DISPLAY 1.595745 (-5200 1475);
PAINT GREEN (-5200 1475);
DISPLAY INVISIBLE (-5200 1475);
FORCEPROP 1 LAST BODY_TYPE PLUMBING
J 0
(-5525 1550);
DISPLAY 1.595745 (-5525 1550);
PAINT GREEN (-5525 1550);
DISPLAY INVISIBLE (-5525 1550);
FORCEPROP 2 LAST CDS_LIB mstr_standard
J 0
(-5525 1600);
PAINT MONO (-5525 1600);
DISPLAY INVISIBLE (-5525 1600);
FORCEPROP 1 LAST PATH I23
J 0
(-5527 1600);
DISPLAY 0.872340 (-5527 1600);
PAINT GREEN (-5527 1600);
DISPLAY INVISIBLE (-5527 1600);
FORCEADD TAP..6
(-5525 1650);
FORCEPROP 3 LASTPIN (-5475 1650) SIG_NAME M_B_DQ<3>
J 0
(-5465 1660);
DISPLAY 0.659574 (-5465 1660);
PAINT MONO (-5465 1660);
DISPLAY INVISIBLE (-5465 1660);
FORCEPROP 1 LASTPIN (-5475 1650) BN 3
J 0
(-5527 1658);
DISPLAY 0.617021 (-5527 1658);
PAINT PINK (-5527 1658);
FORCEPROP 1 LAST HDL_TAP TRUE
J 0
(-5200 1525);
DISPLAY 1.595745 (-5200 1525);
PAINT GREEN (-5200 1525);
DISPLAY INVISIBLE (-5200 1525);
FORCEPROP 1 LAST BODY_TYPE PLUMBING
J 0
(-5525 1600);
DISPLAY 1.595745 (-5525 1600);
PAINT GREEN (-5525 1600);
DISPLAY INVISIBLE (-5525 1600);
FORCEPROP 2 LAST CDS_LIB mstr_standard
J 0
(-5525 1650);
PAINT MONO (-5525 1650);
DISPLAY INVISIBLE (-5525 1650);
FORCEPROP 1 LAST PATH I24
J 0
(-5527 1650);
DISPLAY 0.872340 (-5527 1650);
PAINT GREEN (-5527 1650);
DISPLAY INVISIBLE (-5527 1650);
FORCEADD TAP..6
(-5525 1700);
FORCEPROP 3 LASTPIN (-5475 1700) SIG_NAME M_B_DQ<4>
J 0
(-5465 1710);
DISPLAY 0.659574 (-5465 1710);
PAINT MONO (-5465 1710);
DISPLAY INVISIBLE (-5465 1710);
FORCEPROP 1 LASTPIN (-5475 1700) BN 4
J 0
(-5527 1708);
DISPLAY 0.617021 (-5527 1708);
PAINT PINK (-5527 1708);
FORCEPROP 1 LAST HDL_TAP TRUE
J 0
(-5200 1575);
DISPLAY 1.595745 (-5200 1575);
PAINT GREEN (-5200 1575);
DISPLAY INVISIBLE (-5200 1575);
FORCEPROP 1 LAST BODY_TYPE PLUMBING
J 0
(-5525 1650);
DISPLAY 1.595745 (-5525 1650);
PAINT GREEN (-5525 1650);
DISPLAY INVISIBLE (-5525 1650);
FORCEPROP 2 LAST CDS_LIB mstr_standard
J 0
(-5525 1700);
PAINT MONO (-5525 1700);
DISPLAY INVISIBLE (-5525 1700);
FORCEPROP 1 LAST PATH I25
J 0
(-5527 1700);
DISPLAY 0.872340 (-5527 1700);
PAINT GREEN (-5527 1700);
DISPLAY INVISIBLE (-5527 1700);
FORCEADD TAP..6
(-5525 1750);
FORCEPROP 3 LASTPIN (-5475 1750) SIG_NAME M_B_DQ<5>
J 0
(-5465 1760);
DISPLAY 0.659574 (-5465 1760);
PAINT MONO (-5465 1760);
DISPLAY INVISIBLE (-5465 1760);
FORCEPROP 1 LASTPIN (-5475 1750) BN 5
J 0
(-5527 1758);
DISPLAY 0.617021 (-5527 1758);
PAINT PINK (-5527 1758);
FORCEPROP 1 LAST HDL_TAP TRUE
J 0
(-5200 1625);
DISPLAY 1.595745 (-5200 1625);
PAINT GREEN (-5200 1625);
DISPLAY INVISIBLE (-5200 1625);
FORCEPROP 1 LAST BODY_TYPE PLUMBING
J 0
(-5525 1700);
DISPLAY 1.595745 (-5525 1700);
PAINT GREEN (-5525 1700);
DISPLAY INVISIBLE (-5525 1700);
FORCEPROP 2 LAST CDS_LIB mstr_standard
J 0
(-5525 1750);
PAINT MONO (-5525 1750);
DISPLAY INVISIBLE (-5525 1750);
FORCEPROP 1 LAST PATH I26
J 0
(-5527 1750);
DISPLAY 0.872340 (-5527 1750);
PAINT GREEN (-5527 1750);
DISPLAY INVISIBLE (-5527 1750);
FORCEADD TAP..6
(-5525 1800);
FORCEPROP 3 LASTPIN (-5475 1800) SIG_NAME M_B_DQ<6>
J 0
(-5465 1810);
DISPLAY 0.659574 (-5465 1810);
PAINT MONO (-5465 1810);
DISPLAY INVISIBLE (-5465 1810);
FORCEPROP 1 LASTPIN (-5475 1800) BN 6
J 0
(-5527 1808);
DISPLAY 0.617021 (-5527 1808);
PAINT PINK (-5527 1808);
FORCEPROP 1 LAST HDL_TAP TRUE
J 0
(-5200 1675);
DISPLAY 1.595745 (-5200 1675);
PAINT GREEN (-5200 1675);
DISPLAY INVISIBLE (-5200 1675);
FORCEPROP 1 LAST BODY_TYPE PLUMBING
J 0
(-5525 1750);
DISPLAY 1.595745 (-5525 1750);
PAINT GREEN (-5525 1750);
DISPLAY INVISIBLE (-5525 1750);
FORCEPROP 2 LAST CDS_LIB mstr_standard
J 0
(-5525 1800);
PAINT MONO (-5525 1800);
DISPLAY INVISIBLE (-5525 1800);
FORCEPROP 1 LAST PATH I27
J 0
(-5527 1800);
DISPLAY 0.872340 (-5527 1800);
PAINT GREEN (-5527 1800);
DISPLAY INVISIBLE (-5527 1800);
FORCEADD TAP..6
(-5525 1850);
FORCEPROP 3 LASTPIN (-5475 1850) SIG_NAME M_B_DQ<7>
J 0
(-5465 1860);
DISPLAY 0.659574 (-5465 1860);
PAINT MONO (-5465 1860);
DISPLAY INVISIBLE (-5465 1860);
FORCEPROP 1 LASTPIN (-5475 1850) BN 7
J 0
(-5527 1858);
DISPLAY 0.617021 (-5527 1858);
PAINT PINK (-5527 1858);
FORCEPROP 1 LAST HDL_TAP TRUE
J 0
(-5200 1725);
DISPLAY 1.595745 (-5200 1725);
PAINT GREEN (-5200 1725);
DISPLAY INVISIBLE (-5200 1725);
FORCEPROP 1 LAST BODY_TYPE PLUMBING
J 0
(-5525 1800);
DISPLAY 1.595745 (-5525 1800);
PAINT GREEN (-5525 1800);
DISPLAY INVISIBLE (-5525 1800);
FORCEPROP 2 LAST CDS_LIB mstr_standard
J 0
(-5525 1850);
PAINT MONO (-5525 1850);
DISPLAY INVISIBLE (-5525 1850);
FORCEPROP 1 LAST PATH I28
J 0
(-5527 1850);
DISPLAY 0.872340 (-5527 1850);
PAINT GREEN (-5527 1850);
DISPLAY INVISIBLE (-5527 1850);
FORCEADD TAP..6
(-5525 1900);
FORCEPROP 3 LASTPIN (-5475 1900) SIG_NAME M_B_DQ<8>
J 0
(-5465 1910);
DISPLAY 0.659574 (-5465 1910);
PAINT MONO (-5465 1910);
DISPLAY INVISIBLE (-5465 1910);
FORCEPROP 1 LASTPIN (-5475 1900) BN 8
J 0
(-5527 1908);
DISPLAY 0.617021 (-5527 1908);
PAINT PINK (-5527 1908);
FORCEPROP 1 LAST HDL_TAP TRUE
J 0
(-5200 1775);
DISPLAY 1.595745 (-5200 1775);
PAINT GREEN (-5200 1775);
DISPLAY INVISIBLE (-5200 1775);
FORCEPROP 1 LAST BODY_TYPE PLUMBING
J 0
(-5525 1850);
DISPLAY 1.595745 (-5525 1850);
PAINT GREEN (-5525 1850);
DISPLAY INVISIBLE (-5525 1850);
FORCEPROP 2 LAST CDS_LIB mstr_standard
J 0
(-5525 1900);
PAINT MONO (-5525 1900);
DISPLAY INVISIBLE (-5525 1900);
FORCEPROP 1 LAST PATH I29
J 0
(-5527 1900);
DISPLAY 0.872340 (-5527 1900);
PAINT GREEN (-5527 1900);
DISPLAY INVISIBLE (-5527 1900);
FORCEADD OFFPAGE..5
(-6375 1000);
FORCEPROP 2 LAST $XR1 46 
J 0
(-6719 1000);
DISPLAY 0.638298 (-6719 1000);
PAINT MONO (-6719 1000);
FORCEPROP 2 LAST $XR0 45 
J 0
(-6629 1000);
DISPLAY 0.638298 (-6629 1000);
PAINT MONO (-6629 1000);
FORCEPROP 1 LAST COMMENT_BODY TRUE
J 0
(-6275 925);
DISPLAY 1.170213 (-6275 925);
PAINT GREEN (-6275 925);
DISPLAY INVISIBLE (-6275 925);
FORCEPROP 1 LAST OFFPAGE TRUE
J 0
(-6050 875);
DISPLAY 1.170213 (-6050 875);
PAINT GREEN (-6050 875);
DISPLAY INVISIBLE (-6050 875);
FORCEPROP 2 LAST CDS_LIB mstr_standard
J 0
(-6375 1000);
PAINT MONO (-6375 1000);
DISPLAY INVISIBLE (-6375 1000);
FORCEPROP 2 LAST PATH I3
J 0
(-6325 1075);
DISPLAY 1.021277 (-6325 1075);
PAINT ORANGE (-6325 1075);
DISPLAY INVISIBLE (-6325 1075);
FORCEADD TAP..6
(-5525 2000);
FORCEPROP 3 LASTPIN (-5475 2000) SIG_NAME M_B_DQ<10>
J 0
(-5465 2010);
DISPLAY 0.659574 (-5465 2010);
PAINT MONO (-5465 2010);
DISPLAY INVISIBLE (-5465 2010);
FORCEPROP 1 LASTPIN (-5475 2000) BN 10
J 0
(-5527 2008);
DISPLAY 0.617021 (-5527 2008);
PAINT PINK (-5527 2008);
FORCEPROP 1 LAST HDL_TAP TRUE
J 0
(-5200 1875);
DISPLAY 1.595745 (-5200 1875);
PAINT GREEN (-5200 1875);
DISPLAY INVISIBLE (-5200 1875);
FORCEPROP 1 LAST BODY_TYPE PLUMBING
J 0
(-5525 1950);
DISPLAY 1.595745 (-5525 1950);
PAINT GREEN (-5525 1950);
DISPLAY INVISIBLE (-5525 1950);
FORCEPROP 2 LAST CDS_LIB mstr_standard
J 0
(-5525 2000);
PAINT MONO (-5525 2000);
DISPLAY INVISIBLE (-5525 2000);
FORCEPROP 1 LAST PATH I31
J 0
(-5527 2000);
DISPLAY 0.872340 (-5527 2000);
PAINT GREEN (-5527 2000);
DISPLAY INVISIBLE (-5527 2000);
FORCEADD TAP..6
(-5525 1950);
FORCEPROP 3 LASTPIN (-5475 1950) SIG_NAME M_B_DQ<9>
J 0
(-5465 1960);
DISPLAY 0.659574 (-5465 1960);
PAINT MONO (-5465 1960);
DISPLAY INVISIBLE (-5465 1960);
FORCEPROP 1 LASTPIN (-5475 1950) BN 9
J 0
(-5527 1958);
DISPLAY 0.617021 (-5527 1958);
PAINT PINK (-5527 1958);
FORCEPROP 1 LAST HDL_TAP TRUE
J 0
(-5200 1825);
DISPLAY 1.595745 (-5200 1825);
PAINT GREEN (-5200 1825);
DISPLAY INVISIBLE (-5200 1825);
FORCEPROP 1 LAST BODY_TYPE PLUMBING
J 0
(-5525 1900);
DISPLAY 1.595745 (-5525 1900);
PAINT GREEN (-5525 1900);
DISPLAY INVISIBLE (-5525 1900);
FORCEPROP 2 LAST CDS_LIB mstr_standard
J 0
(-5525 1950);
PAINT MONO (-5525 1950);
DISPLAY INVISIBLE (-5525 1950);
FORCEPROP 1 LAST PATH I32
J 0
(-5527 1950);
DISPLAY 0.872340 (-5527 1950);
PAINT GREEN (-5527 1950);
DISPLAY INVISIBLE (-5527 1950);
FORCEADD TAP..6
(-5525 2100);
FORCEPROP 3 LASTPIN (-5475 2100) SIG_NAME M_B_DQ<12>
J 0
(-5465 2110);
DISPLAY 0.659574 (-5465 2110);
PAINT MONO (-5465 2110);
DISPLAY INVISIBLE (-5465 2110);
FORCEPROP 1 LASTPIN (-5475 2100) BN 12
J 0
(-5527 2108);
DISPLAY 0.617021 (-5527 2108);
PAINT PINK (-5527 2108);
FORCEPROP 1 LAST HDL_TAP TRUE
J 0
(-5200 1975);
DISPLAY 1.595745 (-5200 1975);
PAINT GREEN (-5200 1975);
DISPLAY INVISIBLE (-5200 1975);
FORCEPROP 1 LAST BODY_TYPE PLUMBING
J 0
(-5525 2050);
DISPLAY 1.595745 (-5525 2050);
PAINT GREEN (-5525 2050);
DISPLAY INVISIBLE (-5525 2050);
FORCEPROP 2 LAST CDS_LIB mstr_standard
J 0
(-5525 2100);
PAINT MONO (-5525 2100);
DISPLAY INVISIBLE (-5525 2100);
FORCEPROP 1 LAST PATH I33
J 0
(-5527 2100);
DISPLAY 0.872340 (-5527 2100);
PAINT GREEN (-5527 2100);
DISPLAY INVISIBLE (-5527 2100);
FORCEADD TAP..6
(-5525 2150);
FORCEPROP 3 LASTPIN (-5475 2150) SIG_NAME M_B_DQ<13>
J 0
(-5465 2160);
DISPLAY 0.659574 (-5465 2160);
PAINT MONO (-5465 2160);
DISPLAY INVISIBLE (-5465 2160);
FORCEPROP 1 LASTPIN (-5475 2150) BN 13
J 0
(-5527 2158);
DISPLAY 0.617021 (-5527 2158);
PAINT PINK (-5527 2158);
FORCEPROP 1 LAST HDL_TAP TRUE
J 0
(-5200 2025);
DISPLAY 1.595745 (-5200 2025);
PAINT GREEN (-5200 2025);
DISPLAY INVISIBLE (-5200 2025);
FORCEPROP 1 LAST BODY_TYPE PLUMBING
J 0
(-5525 2100);
DISPLAY 1.595745 (-5525 2100);
PAINT GREEN (-5525 2100);
DISPLAY INVISIBLE (-5525 2100);
FORCEPROP 2 LAST CDS_LIB mstr_standard
J 0
(-5525 2150);
PAINT MONO (-5525 2150);
DISPLAY INVISIBLE (-5525 2150);
FORCEPROP 1 LAST PATH I34
J 0
(-5527 2150);
DISPLAY 0.872340 (-5527 2150);
PAINT GREEN (-5527 2150);
DISPLAY INVISIBLE (-5527 2150);
FORCEADD TAP..6
(-5525 2050);
FORCEPROP 3 LASTPIN (-5475 2050) SIG_NAME M_B_DQ<11>
J 0
(-5465 2060);
DISPLAY 0.659574 (-5465 2060);
PAINT MONO (-5465 2060);
DISPLAY INVISIBLE (-5465 2060);
FORCEPROP 1 LASTPIN (-5475 2050) BN 11
J 0
(-5527 2058);
DISPLAY 0.617021 (-5527 2058);
PAINT PINK (-5527 2058);
FORCEPROP 1 LAST HDL_TAP TRUE
J 0
(-5200 1925);
DISPLAY 1.595745 (-5200 1925);
PAINT GREEN (-5200 1925);
DISPLAY INVISIBLE (-5200 1925);
FORCEPROP 1 LAST BODY_TYPE PLUMBING
J 0
(-5525 2000);
DISPLAY 1.595745 (-5525 2000);
PAINT GREEN (-5525 2000);
DISPLAY INVISIBLE (-5525 2000);
FORCEPROP 2 LAST CDS_LIB mstr_standard
J 0
(-5525 2050);
PAINT MONO (-5525 2050);
DISPLAY INVISIBLE (-5525 2050);
FORCEPROP 1 LAST PATH I35
J 0
(-5527 2050);
DISPLAY 0.872340 (-5527 2050);
PAINT GREEN (-5527 2050);
DISPLAY INVISIBLE (-5527 2050);
FORCEADD TAP..6
(-5525 2200);
FORCEPROP 3 LASTPIN (-5475 2200) SIG_NAME M_B_DQ<14>
J 0
(-5465 2210);
DISPLAY 0.659574 (-5465 2210);
PAINT MONO (-5465 2210);
DISPLAY INVISIBLE (-5465 2210);
FORCEPROP 1 LASTPIN (-5475 2200) BN 14
J 0
(-5527 2208);
DISPLAY 0.617021 (-5527 2208);
PAINT PINK (-5527 2208);
FORCEPROP 1 LAST HDL_TAP TRUE
J 0
(-5200 2075);
DISPLAY 1.595745 (-5200 2075);
PAINT GREEN (-5200 2075);
DISPLAY INVISIBLE (-5200 2075);
FORCEPROP 1 LAST BODY_TYPE PLUMBING
J 0
(-5525 2150);
DISPLAY 1.595745 (-5525 2150);
PAINT GREEN (-5525 2150);
DISPLAY INVISIBLE (-5525 2150);
FORCEPROP 2 LAST CDS_LIB mstr_standard
J 0
(-5525 2200);
PAINT MONO (-5525 2200);
DISPLAY INVISIBLE (-5525 2200);
FORCEPROP 1 LAST PATH I36
J 0
(-5527 2200);
DISPLAY 0.872340 (-5527 2200);
PAINT GREEN (-5527 2200);
DISPLAY INVISIBLE (-5527 2200);
FORCEADD TAP..6
(-5525 2250);
FORCEPROP 3 LASTPIN (-5475 2250) SIG_NAME M_B_DQ<15>
J 0
(-5465 2260);
DISPLAY 0.659574 (-5465 2260);
PAINT MONO (-5465 2260);
DISPLAY INVISIBLE (-5465 2260);
FORCEPROP 1 LASTPIN (-5475 2250) BN 15
J 0
(-5527 2258);
DISPLAY 0.617021 (-5527 2258);
PAINT PINK (-5527 2258);
FORCEPROP 1 LAST HDL_TAP TRUE
J 0
(-5200 2125);
DISPLAY 1.595745 (-5200 2125);
PAINT GREEN (-5200 2125);
DISPLAY INVISIBLE (-5200 2125);
FORCEPROP 1 LAST BODY_TYPE PLUMBING
J 0
(-5525 2200);
DISPLAY 1.595745 (-5525 2200);
PAINT GREEN (-5525 2200);
DISPLAY INVISIBLE (-5525 2200);
FORCEPROP 2 LAST CDS_LIB mstr_standard
J 0
(-5525 2250);
PAINT MONO (-5525 2250);
DISPLAY INVISIBLE (-5525 2250);
FORCEPROP 1 LAST PATH I37
J 0
(-5527 2250);
DISPLAY 0.872340 (-5527 2250);
PAINT GREEN (-5527 2250);
DISPLAY INVISIBLE (-5527 2250);
FORCEADD TAP..6
(-5525 2300);
FORCEPROP 3 LASTPIN (-5475 2300) SIG_NAME M_B_DQ<16>
J 0
(-5465 2310);
DISPLAY 0.659574 (-5465 2310);
PAINT MONO (-5465 2310);
DISPLAY INVISIBLE (-5465 2310);
FORCEPROP 1 LASTPIN (-5475 2300) BN 16
J 0
(-5527 2308);
DISPLAY 0.617021 (-5527 2308);
PAINT PINK (-5527 2308);
FORCEPROP 1 LAST HDL_TAP TRUE
J 0
(-5200 2175);
DISPLAY 1.595745 (-5200 2175);
PAINT GREEN (-5200 2175);
DISPLAY INVISIBLE (-5200 2175);
FORCEPROP 1 LAST BODY_TYPE PLUMBING
J 0
(-5525 2250);
DISPLAY 1.595745 (-5525 2250);
PAINT GREEN (-5525 2250);
DISPLAY INVISIBLE (-5525 2250);
FORCEPROP 2 LAST CDS_LIB mstr_standard
J 0
(-5525 2300);
PAINT MONO (-5525 2300);
DISPLAY INVISIBLE (-5525 2300);
FORCEPROP 1 LAST PATH I38
J 0
(-5527 2300);
DISPLAY 0.872340 (-5527 2300);
PAINT GREEN (-5527 2300);
DISPLAY INVISIBLE (-5527 2300);
FORCEADD TAP..6
(-5525 2350);
FORCEPROP 3 LASTPIN (-5475 2350) SIG_NAME M_B_DQ<17>
J 0
(-5465 2360);
DISPLAY 0.659574 (-5465 2360);
PAINT MONO (-5465 2360);
DISPLAY INVISIBLE (-5465 2360);
FORCEPROP 1 LASTPIN (-5475 2350) BN 17
J 0
(-5527 2358);
DISPLAY 0.617021 (-5527 2358);
PAINT PINK (-5527 2358);
FORCEPROP 1 LAST HDL_TAP TRUE
J 0
(-5200 2225);
DISPLAY 1.595745 (-5200 2225);
PAINT GREEN (-5200 2225);
DISPLAY INVISIBLE (-5200 2225);
FORCEPROP 1 LAST BODY_TYPE PLUMBING
J 0
(-5525 2300);
DISPLAY 1.595745 (-5525 2300);
PAINT GREEN (-5525 2300);
DISPLAY INVISIBLE (-5525 2300);
FORCEPROP 2 LAST CDS_LIB mstr_standard
J 0
(-5525 2350);
PAINT MONO (-5525 2350);
DISPLAY INVISIBLE (-5525 2350);
FORCEPROP 1 LAST PATH I39
J 0
(-5527 2350);
DISPLAY 0.872340 (-5527 2350);
PAINT GREEN (-5527 2350);
DISPLAY INVISIBLE (-5527 2350);
FORCEADD OFFPAGE..6
(-6375 1450);
FORCEPROP 2 LAST $XR1 46 
J 0
(-6744 1450);
DISPLAY 0.638298 (-6744 1450);
PAINT MONO (-6744 1450);
FORCEPROP 2 LAST $XR0 45 
J 0
(-6654 1450);
DISPLAY 0.638298 (-6654 1450);
PAINT MONO (-6654 1450);
FORCEPROP 1 LAST COMMENT_BODY TRUE
J 0
(-6275 1375);
DISPLAY 1.170213 (-6275 1375);
PAINT GREEN (-6275 1375);
DISPLAY INVISIBLE (-6275 1375);
FORCEPROP 1 LAST OFFPAGE TRUE
J 0
(-6050 1325);
DISPLAY 1.170213 (-6050 1325);
PAINT GREEN (-6050 1325);
DISPLAY INVISIBLE (-6050 1325);
FORCEPROP 2 LAST CDS_LIB mstr_standard
J 0
(-6375 1450);
PAINT MONO (-6375 1450);
DISPLAY INVISIBLE (-6375 1450);
FORCEPROP 2 LAST PATH I4
J 0
(-6325 1525);
DISPLAY 1.021277 (-6325 1525);
PAINT ORANGE (-6325 1525);
DISPLAY INVISIBLE (-6325 1525);
FORCEADD TAP..6
(-5525 2400);
FORCEPROP 3 LASTPIN (-5475 2400) SIG_NAME M_B_DQ<18>
J 0
(-5465 2410);
DISPLAY 0.659574 (-5465 2410);
PAINT MONO (-5465 2410);
DISPLAY INVISIBLE (-5465 2410);
FORCEPROP 1 LASTPIN (-5475 2400) BN 18
J 0
(-5527 2408);
DISPLAY 0.617021 (-5527 2408);
PAINT PINK (-5527 2408);
FORCEPROP 1 LAST HDL_TAP TRUE
J 0
(-5200 2275);
DISPLAY 1.595745 (-5200 2275);
PAINT GREEN (-5200 2275);
DISPLAY INVISIBLE (-5200 2275);
FORCEPROP 1 LAST BODY_TYPE PLUMBING
J 0
(-5525 2350);
DISPLAY 1.595745 (-5525 2350);
PAINT GREEN (-5525 2350);
DISPLAY INVISIBLE (-5525 2350);
FORCEPROP 2 LAST CDS_LIB mstr_standard
J 0
(-5525 2400);
PAINT MONO (-5525 2400);
DISPLAY INVISIBLE (-5525 2400);
FORCEPROP 1 LAST PATH I40
J 0
(-5527 2400);
DISPLAY 0.872340 (-5527 2400);
PAINT GREEN (-5527 2400);
DISPLAY INVISIBLE (-5527 2400);
FORCEADD TAP..6
(-5525 2500);
FORCEPROP 3 LASTPIN (-5475 2500) SIG_NAME M_B_DQ<20>
J 0
(-5465 2510);
DISPLAY 0.659574 (-5465 2510);
PAINT MONO (-5465 2510);
DISPLAY INVISIBLE (-5465 2510);
FORCEPROP 1 LASTPIN (-5475 2500) BN 20
J 0
(-5527 2508);
DISPLAY 0.617021 (-5527 2508);
PAINT PINK (-5527 2508);
FORCEPROP 1 LAST HDL_TAP TRUE
J 0
(-5200 2375);
DISPLAY 1.595745 (-5200 2375);
PAINT GREEN (-5200 2375);
DISPLAY INVISIBLE (-5200 2375);
FORCEPROP 1 LAST BODY_TYPE PLUMBING
J 0
(-5525 2450);
DISPLAY 1.595745 (-5525 2450);
PAINT GREEN (-5525 2450);
DISPLAY INVISIBLE (-5525 2450);
FORCEPROP 2 LAST CDS_LIB mstr_standard
J 0
(-5525 2500);
PAINT MONO (-5525 2500);
DISPLAY INVISIBLE (-5525 2500);
FORCEPROP 1 LAST PATH I41
J 0
(-5527 2500);
DISPLAY 0.872340 (-5527 2500);
PAINT GREEN (-5527 2500);
DISPLAY INVISIBLE (-5527 2500);
FORCEADD TAP..6
(-5525 2450);
FORCEPROP 3 LASTPIN (-5475 2450) SIG_NAME M_B_DQ<19>
J 0
(-5465 2460);
DISPLAY 0.659574 (-5465 2460);
PAINT MONO (-5465 2460);
DISPLAY INVISIBLE (-5465 2460);
FORCEPROP 1 LASTPIN (-5475 2450) BN 19
J 0
(-5527 2458);
DISPLAY 0.617021 (-5527 2458);
PAINT PINK (-5527 2458);
FORCEPROP 1 LAST HDL_TAP TRUE
J 0
(-5200 2325);
DISPLAY 1.595745 (-5200 2325);
PAINT GREEN (-5200 2325);
DISPLAY INVISIBLE (-5200 2325);
FORCEPROP 1 LAST BODY_TYPE PLUMBING
J 0
(-5525 2400);
DISPLAY 1.595745 (-5525 2400);
PAINT GREEN (-5525 2400);
DISPLAY INVISIBLE (-5525 2400);
FORCEPROP 2 LAST CDS_LIB mstr_standard
J 0
(-5525 2450);
PAINT MONO (-5525 2450);
DISPLAY INVISIBLE (-5525 2450);
FORCEPROP 1 LAST PATH I42
J 0
(-5527 2450);
DISPLAY 0.872340 (-5527 2450);
PAINT GREEN (-5527 2450);
DISPLAY INVISIBLE (-5527 2450);
FORCEADD TAP..6
(-5525 2550);
FORCEPROP 3 LASTPIN (-5475 2550) SIG_NAME M_B_DQ<21>
J 0
(-5465 2560);
DISPLAY 0.659574 (-5465 2560);
PAINT MONO (-5465 2560);
DISPLAY INVISIBLE (-5465 2560);
FORCEPROP 1 LASTPIN (-5475 2550) BN 21
J 0
(-5527 2558);
DISPLAY 0.617021 (-5527 2558);
PAINT PINK (-5527 2558);
FORCEPROP 1 LAST HDL_TAP TRUE
J 0
(-5200 2425);
DISPLAY 1.595745 (-5200 2425);
PAINT GREEN (-5200 2425);
DISPLAY INVISIBLE (-5200 2425);
FORCEPROP 1 LAST BODY_TYPE PLUMBING
J 0
(-5525 2500);
DISPLAY 1.595745 (-5525 2500);
PAINT GREEN (-5525 2500);
DISPLAY INVISIBLE (-5525 2500);
FORCEPROP 2 LAST CDS_LIB mstr_standard
J 0
(-5525 2550);
PAINT MONO (-5525 2550);
DISPLAY INVISIBLE (-5525 2550);
FORCEPROP 1 LAST PATH I43
J 0
(-5527 2550);
DISPLAY 0.872340 (-5527 2550);
PAINT GREEN (-5527 2550);
DISPLAY INVISIBLE (-5527 2550);
FORCEADD TAP..6
(-5525 2600);
FORCEPROP 3 LASTPIN (-5475 2600) SIG_NAME M_B_DQ<22>
J 0
(-5465 2610);
DISPLAY 0.659574 (-5465 2610);
PAINT MONO (-5465 2610);
DISPLAY INVISIBLE (-5465 2610);
FORCEPROP 1 LASTPIN (-5475 2600) BN 22
J 0
(-5527 2608);
DISPLAY 0.617021 (-5527 2608);
PAINT PINK (-5527 2608);
FORCEPROP 1 LAST HDL_TAP TRUE
J 0
(-5200 2475);
DISPLAY 1.595745 (-5200 2475);
PAINT GREEN (-5200 2475);
DISPLAY INVISIBLE (-5200 2475);
FORCEPROP 1 LAST BODY_TYPE PLUMBING
J 0
(-5525 2550);
DISPLAY 1.595745 (-5525 2550);
PAINT GREEN (-5525 2550);
DISPLAY INVISIBLE (-5525 2550);
FORCEPROP 2 LAST CDS_LIB mstr_standard
J 0
(-5525 2600);
PAINT MONO (-5525 2600);
DISPLAY INVISIBLE (-5525 2600);
FORCEPROP 1 LAST PATH I44
J 0
(-5527 2600);
DISPLAY 0.872340 (-5527 2600);
PAINT GREEN (-5527 2600);
DISPLAY INVISIBLE (-5527 2600);
FORCEADD TAP..6
(-5525 2650);
FORCEPROP 3 LASTPIN (-5475 2650) SIG_NAME M_B_DQ<23>
J 0
(-5465 2660);
DISPLAY 0.659574 (-5465 2660);
PAINT MONO (-5465 2660);
DISPLAY INVISIBLE (-5465 2660);
FORCEPROP 1 LASTPIN (-5475 2650) BN 23
J 0
(-5527 2658);
DISPLAY 0.617021 (-5527 2658);
PAINT PINK (-5527 2658);
FORCEPROP 1 LAST HDL_TAP TRUE
J 0
(-5200 2525);
DISPLAY 1.595745 (-5200 2525);
PAINT GREEN (-5200 2525);
DISPLAY INVISIBLE (-5200 2525);
FORCEPROP 1 LAST BODY_TYPE PLUMBING
J 0
(-5525 2600);
DISPLAY 1.595745 (-5525 2600);
PAINT GREEN (-5525 2600);
DISPLAY INVISIBLE (-5525 2600);
FORCEPROP 2 LAST CDS_LIB mstr_standard
J 0
(-5525 2650);
PAINT MONO (-5525 2650);
DISPLAY INVISIBLE (-5525 2650);
FORCEPROP 1 LAST PATH I45
J 0
(-5527 2650);
DISPLAY 0.872340 (-5527 2650);
PAINT GREEN (-5527 2650);
DISPLAY INVISIBLE (-5527 2650);
FORCEADD TAP..6
(-5525 2700);
FORCEPROP 3 LASTPIN (-5475 2700) SIG_NAME M_B_DQ<24>
J 0
(-5465 2710);
DISPLAY 0.659574 (-5465 2710);
PAINT MONO (-5465 2710);
DISPLAY INVISIBLE (-5465 2710);
FORCEPROP 1 LASTPIN (-5475 2700) BN 24
J 0
(-5527 2708);
DISPLAY 0.617021 (-5527 2708);
PAINT PINK (-5527 2708);
FORCEPROP 1 LAST HDL_TAP TRUE
J 0
(-5200 2575);
DISPLAY 1.595745 (-5200 2575);
PAINT GREEN (-5200 2575);
DISPLAY INVISIBLE (-5200 2575);
FORCEPROP 1 LAST BODY_TYPE PLUMBING
J 0
(-5525 2650);
DISPLAY 1.595745 (-5525 2650);
PAINT GREEN (-5525 2650);
DISPLAY INVISIBLE (-5525 2650);
FORCEPROP 2 LAST CDS_LIB mstr_standard
J 0
(-5525 2700);
PAINT MONO (-5525 2700);
DISPLAY INVISIBLE (-5525 2700);
FORCEPROP 1 LAST PATH I46
J 0
(-5527 2700);
DISPLAY 0.872340 (-5527 2700);
PAINT GREEN (-5527 2700);
DISPLAY INVISIBLE (-5527 2700);
FORCEADD TAP..6
(-5525 2750);
FORCEPROP 3 LASTPIN (-5475 2750) SIG_NAME M_B_DQ<25>
J 0
(-5465 2760);
DISPLAY 0.659574 (-5465 2760);
PAINT MONO (-5465 2760);
DISPLAY INVISIBLE (-5465 2760);
FORCEPROP 1 LASTPIN (-5475 2750) BN 25
J 0
(-5527 2758);
DISPLAY 0.617021 (-5527 2758);
PAINT PINK (-5527 2758);
FORCEPROP 1 LAST HDL_TAP TRUE
J 0
(-5200 2625);
DISPLAY 1.595745 (-5200 2625);
PAINT GREEN (-5200 2625);
DISPLAY INVISIBLE (-5200 2625);
FORCEPROP 1 LAST BODY_TYPE PLUMBING
J 0
(-5525 2700);
DISPLAY 1.595745 (-5525 2700);
PAINT GREEN (-5525 2700);
DISPLAY INVISIBLE (-5525 2700);
FORCEPROP 2 LAST CDS_LIB mstr_standard
J 0
(-5525 2750);
PAINT MONO (-5525 2750);
DISPLAY INVISIBLE (-5525 2750);
FORCEPROP 1 LAST PATH I47
J 0
(-5527 2750);
DISPLAY 0.872340 (-5527 2750);
PAINT GREEN (-5527 2750);
DISPLAY INVISIBLE (-5527 2750);
FORCEADD TAP..6
(-5525 2800);
FORCEPROP 3 LASTPIN (-5475 2800) SIG_NAME M_B_DQ<26>
J 0
(-5465 2810);
DISPLAY 0.659574 (-5465 2810);
PAINT MONO (-5465 2810);
DISPLAY INVISIBLE (-5465 2810);
FORCEPROP 1 LASTPIN (-5475 2800) BN 26
J 0
(-5527 2808);
DISPLAY 0.617021 (-5527 2808);
PAINT PINK (-5527 2808);
FORCEPROP 1 LAST HDL_TAP TRUE
J 0
(-5200 2675);
DISPLAY 1.595745 (-5200 2675);
PAINT GREEN (-5200 2675);
DISPLAY INVISIBLE (-5200 2675);
FORCEPROP 1 LAST BODY_TYPE PLUMBING
J 0
(-5525 2750);
DISPLAY 1.595745 (-5525 2750);
PAINT GREEN (-5525 2750);
DISPLAY INVISIBLE (-5525 2750);
FORCEPROP 2 LAST CDS_LIB mstr_standard
J 0
(-5525 2800);
PAINT MONO (-5525 2800);
DISPLAY INVISIBLE (-5525 2800);
FORCEPROP 1 LAST PATH I48
J 0
(-5527 2800);
DISPLAY 0.872340 (-5527 2800);
PAINT GREEN (-5527 2800);
DISPLAY INVISIBLE (-5527 2800);
FORCEADD TAP..6
(-5525 2850);
FORCEPROP 3 LASTPIN (-5475 2850) SIG_NAME M_B_DQ<27>
J 0
(-5465 2860);
DISPLAY 0.659574 (-5465 2860);
PAINT MONO (-5465 2860);
DISPLAY INVISIBLE (-5465 2860);
FORCEPROP 1 LASTPIN (-5475 2850) BN 27
J 0
(-5527 2858);
DISPLAY 0.617021 (-5527 2858);
PAINT PINK (-5527 2858);
FORCEPROP 1 LAST HDL_TAP TRUE
J 0
(-5200 2725);
DISPLAY 1.595745 (-5200 2725);
PAINT GREEN (-5200 2725);
DISPLAY INVISIBLE (-5200 2725);
FORCEPROP 1 LAST BODY_TYPE PLUMBING
J 0
(-5525 2800);
DISPLAY 1.595745 (-5525 2800);
PAINT GREEN (-5525 2800);
DISPLAY INVISIBLE (-5525 2800);
FORCEPROP 2 LAST CDS_LIB mstr_standard
J 0
(-5525 2850);
PAINT MONO (-5525 2850);
DISPLAY INVISIBLE (-5525 2850);
FORCEPROP 1 LAST PATH I49
J 0
(-5527 2850);
DISPLAY 0.872340 (-5527 2850);
PAINT GREEN (-5527 2850);
DISPLAY INVISIBLE (-5527 2850);
FORCEADD TAP..6
(-5525 600);
FORCEPROP 3 LASTPIN (-5475 600) SIG_NAME M_B_CLK_DN<0>
J 0
(-5465 610);
DISPLAY 0.659574 (-5465 610);
PAINT MONO (-5465 610);
DISPLAY INVISIBLE (-5465 610);
FORCEPROP 1 LASTPIN (-5475 600) BN 0
J 0
(-5527 608);
DISPLAY 0.617021 (-5527 608);
PAINT PINK (-5527 608);
FORCEPROP 1 LAST HDL_TAP TRUE
J 0
(-5200 475);
DISPLAY 1.595745 (-5200 475);
PAINT GREEN (-5200 475);
DISPLAY INVISIBLE (-5200 475);
FORCEPROP 1 LAST BODY_TYPE PLUMBING
J 0
(-5525 550);
DISPLAY 1.595745 (-5525 550);
PAINT GREEN (-5525 550);
DISPLAY INVISIBLE (-5525 550);
FORCEPROP 2 LAST CDS_LIB mstr_standard
J 0
(-5525 600);
PAINT MONO (-5525 600);
DISPLAY INVISIBLE (-5525 600);
FORCEPROP 1 LAST PATH I5
J 0
(-5527 600);
DISPLAY 0.872340 (-5527 600);
PAINT GREEN (-5527 600);
DISPLAY INVISIBLE (-5527 600);
FORCEADD TAP..6
(-5525 2900);
FORCEPROP 3 LASTPIN (-5475 2900) SIG_NAME M_B_DQ<28>
J 0
(-5465 2910);
DISPLAY 0.659574 (-5465 2910);
PAINT MONO (-5465 2910);
DISPLAY INVISIBLE (-5465 2910);
FORCEPROP 1 LASTPIN (-5475 2900) BN 28
J 0
(-5527 2908);
DISPLAY 0.617021 (-5527 2908);
PAINT PINK (-5527 2908);
FORCEPROP 1 LAST HDL_TAP TRUE
J 0
(-5200 2775);
DISPLAY 1.595745 (-5200 2775);
PAINT GREEN (-5200 2775);
DISPLAY INVISIBLE (-5200 2775);
FORCEPROP 1 LAST BODY_TYPE PLUMBING
J 0
(-5525 2850);
DISPLAY 1.595745 (-5525 2850);
PAINT GREEN (-5525 2850);
DISPLAY INVISIBLE (-5525 2850);
FORCEPROP 2 LAST CDS_LIB mstr_standard
J 0
(-5525 2900);
PAINT MONO (-5525 2900);
DISPLAY INVISIBLE (-5525 2900);
FORCEPROP 1 LAST PATH I50
J 0
(-5527 2900);
DISPLAY 0.872340 (-5527 2900);
PAINT GREEN (-5527 2900);
DISPLAY INVISIBLE (-5527 2900);
FORCEADD TAP..6
(-5525 3000);
FORCEPROP 3 LASTPIN (-5475 3000) SIG_NAME M_B_DQ<30>
J 0
(-5465 3010);
DISPLAY 0.659574 (-5465 3010);
PAINT MONO (-5465 3010);
DISPLAY INVISIBLE (-5465 3010);
FORCEPROP 1 LASTPIN (-5475 3000) BN 30
J 0
(-5527 3008);
DISPLAY 0.617021 (-5527 3008);
PAINT PINK (-5527 3008);
FORCEPROP 1 LAST HDL_TAP TRUE
J 0
(-5200 2875);
DISPLAY 1.595745 (-5200 2875);
PAINT GREEN (-5200 2875);
DISPLAY INVISIBLE (-5200 2875);
FORCEPROP 1 LAST BODY_TYPE PLUMBING
J 0
(-5525 2950);
DISPLAY 1.595745 (-5525 2950);
PAINT GREEN (-5525 2950);
DISPLAY INVISIBLE (-5525 2950);
FORCEPROP 2 LAST CDS_LIB mstr_standard
J 0
(-5525 3000);
PAINT MONO (-5525 3000);
DISPLAY INVISIBLE (-5525 3000);
FORCEPROP 1 LAST PATH I51
J 0
(-5527 3000);
DISPLAY 0.872340 (-5527 3000);
PAINT GREEN (-5527 3000);
DISPLAY INVISIBLE (-5527 3000);
FORCEADD TAP..6
(-5525 2950);
FORCEPROP 3 LASTPIN (-5475 2950) SIG_NAME M_B_DQ<29>
J 0
(-5465 2960);
DISPLAY 0.659574 (-5465 2960);
PAINT MONO (-5465 2960);
DISPLAY INVISIBLE (-5465 2960);
FORCEPROP 1 LASTPIN (-5475 2950) BN 29
J 0
(-5527 2958);
DISPLAY 0.617021 (-5527 2958);
PAINT PINK (-5527 2958);
FORCEPROP 1 LAST HDL_TAP TRUE
J 0
(-5200 2825);
DISPLAY 1.595745 (-5200 2825);
PAINT GREEN (-5200 2825);
DISPLAY INVISIBLE (-5200 2825);
FORCEPROP 1 LAST BODY_TYPE PLUMBING
J 0
(-5525 2900);
DISPLAY 1.595745 (-5525 2900);
PAINT GREEN (-5525 2900);
DISPLAY INVISIBLE (-5525 2900);
FORCEPROP 2 LAST CDS_LIB mstr_standard
J 0
(-5525 2950);
PAINT MONO (-5525 2950);
DISPLAY INVISIBLE (-5525 2950);
FORCEPROP 1 LAST PATH I52
J 0
(-5527 2950);
DISPLAY 0.872340 (-5527 2950);
PAINT GREEN (-5527 2950);
DISPLAY INVISIBLE (-5527 2950);
FORCEADD TAP..6
(-5525 3050);
FORCEPROP 3 LASTPIN (-5475 3050) SIG_NAME M_B_DQ<31>
J 0
(-5465 3060);
DISPLAY 0.659574 (-5465 3060);
PAINT MONO (-5465 3060);
DISPLAY INVISIBLE (-5465 3060);
FORCEPROP 1 LASTPIN (-5475 3050) BN 31
J 0
(-5527 3058);
DISPLAY 0.617021 (-5527 3058);
PAINT PINK (-5527 3058);
FORCEPROP 1 LAST HDL_TAP TRUE
J 0
(-5200 2925);
DISPLAY 1.595745 (-5200 2925);
PAINT GREEN (-5200 2925);
DISPLAY INVISIBLE (-5200 2925);
FORCEPROP 1 LAST BODY_TYPE PLUMBING
J 0
(-5525 3000);
DISPLAY 1.595745 (-5525 3000);
PAINT GREEN (-5525 3000);
DISPLAY INVISIBLE (-5525 3000);
FORCEPROP 2 LAST CDS_LIB mstr_standard
J 0
(-5525 3050);
PAINT MONO (-5525 3050);
DISPLAY INVISIBLE (-5525 3050);
FORCEPROP 1 LAST PATH I53
J 0
(-5527 3050);
DISPLAY 0.872340 (-5527 3050);
PAINT GREEN (-5527 3050);
DISPLAY INVISIBLE (-5527 3050);
FORCEADD TAP..6
(-5525 3100);
FORCEPROP 3 LASTPIN (-5475 3100) SIG_NAME M_B_DQ<32>
J 0
(-5465 3110);
DISPLAY 0.659574 (-5465 3110);
PAINT MONO (-5465 3110);
DISPLAY INVISIBLE (-5465 3110);
FORCEPROP 1 LASTPIN (-5475 3100) BN 32
J 0
(-5527 3108);
DISPLAY 0.617021 (-5527 3108);
PAINT PINK (-5527 3108);
FORCEPROP 1 LAST HDL_TAP TRUE
J 0
(-5200 2975);
DISPLAY 1.595745 (-5200 2975);
PAINT GREEN (-5200 2975);
DISPLAY INVISIBLE (-5200 2975);
FORCEPROP 1 LAST BODY_TYPE PLUMBING
J 0
(-5525 3050);
DISPLAY 1.595745 (-5525 3050);
PAINT GREEN (-5525 3050);
DISPLAY INVISIBLE (-5525 3050);
FORCEPROP 2 LAST CDS_LIB mstr_standard
J 0
(-5525 3100);
PAINT MONO (-5525 3100);
DISPLAY INVISIBLE (-5525 3100);
FORCEPROP 1 LAST PATH I54
J 0
(-5527 3100);
DISPLAY 0.872340 (-5527 3100);
PAINT GREEN (-5527 3100);
DISPLAY INVISIBLE (-5527 3100);
FORCEADD TAP..6
(-5525 3150);
FORCEPROP 3 LASTPIN (-5475 3150) SIG_NAME M_B_DQ<33>
J 0
(-5465 3160);
DISPLAY 0.659574 (-5465 3160);
PAINT MONO (-5465 3160);
DISPLAY INVISIBLE (-5465 3160);
FORCEPROP 1 LASTPIN (-5475 3150) BN 33
J 0
(-5527 3158);
DISPLAY 0.617021 (-5527 3158);
PAINT PINK (-5527 3158);
FORCEPROP 1 LAST HDL_TAP TRUE
J 0
(-5200 3025);
DISPLAY 1.595745 (-5200 3025);
PAINT GREEN (-5200 3025);
DISPLAY INVISIBLE (-5200 3025);
FORCEPROP 1 LAST BODY_TYPE PLUMBING
J 0
(-5525 3100);
DISPLAY 1.595745 (-5525 3100);
PAINT GREEN (-5525 3100);
DISPLAY INVISIBLE (-5525 3100);
FORCEPROP 2 LAST CDS_LIB mstr_standard
J 0
(-5525 3150);
PAINT MONO (-5525 3150);
DISPLAY INVISIBLE (-5525 3150);
FORCEPROP 1 LAST PATH I55
J 0
(-5527 3150);
DISPLAY 0.872340 (-5527 3150);
PAINT GREEN (-5527 3150);
DISPLAY INVISIBLE (-5527 3150);
FORCEADD TAP..6
(-5525 3200);
FORCEPROP 3 LASTPIN (-5475 3200) SIG_NAME M_B_DQ<34>
J 0
(-5465 3210);
DISPLAY 0.659574 (-5465 3210);
PAINT MONO (-5465 3210);
DISPLAY INVISIBLE (-5465 3210);
FORCEPROP 1 LASTPIN (-5475 3200) BN 34
J 0
(-5527 3208);
DISPLAY 0.617021 (-5527 3208);
PAINT PINK (-5527 3208);
FORCEPROP 1 LAST HDL_TAP TRUE
J 0
(-5200 3075);
DISPLAY 1.595745 (-5200 3075);
PAINT GREEN (-5200 3075);
DISPLAY INVISIBLE (-5200 3075);
FORCEPROP 1 LAST BODY_TYPE PLUMBING
J 0
(-5525 3150);
DISPLAY 1.595745 (-5525 3150);
PAINT GREEN (-5525 3150);
DISPLAY INVISIBLE (-5525 3150);
FORCEPROP 2 LAST CDS_LIB mstr_standard
J 0
(-5525 3200);
PAINT MONO (-5525 3200);
DISPLAY INVISIBLE (-5525 3200);
FORCEPROP 1 LAST PATH I56
J 0
(-5527 3200);
DISPLAY 0.872340 (-5527 3200);
PAINT GREEN (-5527 3200);
DISPLAY INVISIBLE (-5527 3200);
FORCEADD TAP..6
(-5525 3300);
FORCEPROP 3 LASTPIN (-5475 3300) SIG_NAME M_B_DQ<36>
J 0
(-5465 3310);
DISPLAY 0.659574 (-5465 3310);
PAINT MONO (-5465 3310);
DISPLAY INVISIBLE (-5465 3310);
FORCEPROP 1 LASTPIN (-5475 3300) BN 36
J 0
(-5527 3308);
DISPLAY 0.617021 (-5527 3308);
PAINT PINK (-5527 3308);
FORCEPROP 1 LAST HDL_TAP TRUE
J 0
(-5200 3175);
DISPLAY 1.595745 (-5200 3175);
PAINT GREEN (-5200 3175);
DISPLAY INVISIBLE (-5200 3175);
FORCEPROP 1 LAST BODY_TYPE PLUMBING
J 0
(-5525 3250);
DISPLAY 1.595745 (-5525 3250);
PAINT GREEN (-5525 3250);
DISPLAY INVISIBLE (-5525 3250);
FORCEPROP 2 LAST CDS_LIB mstr_standard
J 0
(-5525 3300);
PAINT MONO (-5525 3300);
DISPLAY INVISIBLE (-5525 3300);
FORCEPROP 1 LAST PATH I57
J 0
(-5527 3300);
DISPLAY 0.872340 (-5527 3300);
PAINT GREEN (-5527 3300);
DISPLAY INVISIBLE (-5527 3300);
FORCEADD TAP..6
(-5525 3250);
FORCEPROP 3 LASTPIN (-5475 3250) SIG_NAME M_B_DQ<35>
J 0
(-5465 3260);
DISPLAY 0.659574 (-5465 3260);
PAINT MONO (-5465 3260);
DISPLAY INVISIBLE (-5465 3260);
FORCEPROP 1 LASTPIN (-5475 3250) BN 35
J 0
(-5527 3258);
DISPLAY 0.617021 (-5527 3258);
PAINT PINK (-5527 3258);
FORCEPROP 1 LAST HDL_TAP TRUE
J 0
(-5200 3125);
DISPLAY 1.595745 (-5200 3125);
PAINT GREEN (-5200 3125);
DISPLAY INVISIBLE (-5200 3125);
FORCEPROP 1 LAST BODY_TYPE PLUMBING
J 0
(-5525 3200);
DISPLAY 1.595745 (-5525 3200);
PAINT GREEN (-5525 3200);
DISPLAY INVISIBLE (-5525 3200);
FORCEPROP 2 LAST CDS_LIB mstr_standard
J 0
(-5525 3250);
PAINT MONO (-5525 3250);
DISPLAY INVISIBLE (-5525 3250);
FORCEPROP 1 LAST PATH I58
J 0
(-5527 3250);
DISPLAY 0.872340 (-5527 3250);
PAINT GREEN (-5527 3250);
DISPLAY INVISIBLE (-5527 3250);
FORCEADD TAP..6
(-5525 3350);
FORCEPROP 3 LASTPIN (-5475 3350) SIG_NAME M_B_DQ<37>
J 0
(-5465 3360);
DISPLAY 0.659574 (-5465 3360);
PAINT MONO (-5465 3360);
DISPLAY INVISIBLE (-5465 3360);
FORCEPROP 1 LASTPIN (-5475 3350) BN 37
J 0
(-5527 3358);
DISPLAY 0.617021 (-5527 3358);
PAINT PINK (-5527 3358);
FORCEPROP 1 LAST HDL_TAP TRUE
J 0
(-5200 3225);
DISPLAY 1.595745 (-5200 3225);
PAINT GREEN (-5200 3225);
DISPLAY INVISIBLE (-5200 3225);
FORCEPROP 1 LAST BODY_TYPE PLUMBING
J 0
(-5525 3300);
DISPLAY 1.595745 (-5525 3300);
PAINT GREEN (-5525 3300);
DISPLAY INVISIBLE (-5525 3300);
FORCEPROP 2 LAST CDS_LIB mstr_standard
J 0
(-5525 3350);
PAINT MONO (-5525 3350);
DISPLAY INVISIBLE (-5525 3350);
FORCEPROP 1 LAST PATH I59
J 0
(-5527 3350);
DISPLAY 0.872340 (-5527 3350);
PAINT GREEN (-5527 3350);
DISPLAY INVISIBLE (-5527 3350);
FORCEADD TAP..6
(-5525 650);
FORCEPROP 3 LASTPIN (-5475 650) SIG_NAME M_B_CLK_DN<1>
J 0
(-5465 660);
DISPLAY 0.659574 (-5465 660);
PAINT MONO (-5465 660);
DISPLAY INVISIBLE (-5465 660);
FORCEPROP 1 LASTPIN (-5475 650) BN 1
J 0
(-5527 658);
DISPLAY 0.617021 (-5527 658);
PAINT PINK (-5527 658);
FORCEPROP 1 LAST HDL_TAP TRUE
J 0
(-5200 525);
DISPLAY 1.595745 (-5200 525);
PAINT GREEN (-5200 525);
DISPLAY INVISIBLE (-5200 525);
FORCEPROP 1 LAST BODY_TYPE PLUMBING
J 0
(-5525 600);
DISPLAY 1.595745 (-5525 600);
PAINT GREEN (-5525 600);
DISPLAY INVISIBLE (-5525 600);
FORCEPROP 2 LAST CDS_LIB mstr_standard
J 0
(-5525 650);
PAINT MONO (-5525 650);
DISPLAY INVISIBLE (-5525 650);
FORCEPROP 1 LAST PATH I6
J 0
(-5527 650);
DISPLAY 0.872340 (-5527 650);
PAINT GREEN (-5527 650);
DISPLAY INVISIBLE (-5527 650);
FORCEADD TAP..6
(-5525 3400);
FORCEPROP 3 LASTPIN (-5475 3400) SIG_NAME M_B_DQ<38>
J 0
(-5465 3410);
DISPLAY 0.659574 (-5465 3410);
PAINT MONO (-5465 3410);
DISPLAY INVISIBLE (-5465 3410);
FORCEPROP 1 LASTPIN (-5475 3400) BN 38
J 0
(-5527 3408);
DISPLAY 0.617021 (-5527 3408);
PAINT PINK (-5527 3408);
FORCEPROP 1 LAST HDL_TAP TRUE
J 0
(-5200 3275);
DISPLAY 1.595745 (-5200 3275);
PAINT GREEN (-5200 3275);
DISPLAY INVISIBLE (-5200 3275);
FORCEPROP 1 LAST BODY_TYPE PLUMBING
J 0
(-5525 3350);
DISPLAY 1.595745 (-5525 3350);
PAINT GREEN (-5525 3350);
DISPLAY INVISIBLE (-5525 3350);
FORCEPROP 2 LAST CDS_LIB mstr_standard
J 0
(-5525 3400);
PAINT MONO (-5525 3400);
DISPLAY INVISIBLE (-5525 3400);
FORCEPROP 1 LAST PATH I60
J 0
(-5527 3400);
DISPLAY 0.872340 (-5527 3400);
PAINT GREEN (-5527 3400);
DISPLAY INVISIBLE (-5527 3400);
FORCEADD TAP..6
(-5525 3450);
FORCEPROP 3 LASTPIN (-5475 3450) SIG_NAME M_B_DQ<39>
J 0
(-5465 3460);
DISPLAY 0.659574 (-5465 3460);
PAINT MONO (-5465 3460);
DISPLAY INVISIBLE (-5465 3460);
FORCEPROP 1 LASTPIN (-5475 3450) BN 39
J 0
(-5527 3458);
DISPLAY 0.617021 (-5527 3458);
PAINT PINK (-5527 3458);
FORCEPROP 1 LAST HDL_TAP TRUE
J 0
(-5200 3325);
DISPLAY 1.595745 (-5200 3325);
PAINT GREEN (-5200 3325);
DISPLAY INVISIBLE (-5200 3325);
FORCEPROP 1 LAST BODY_TYPE PLUMBING
J 0
(-5525 3400);
DISPLAY 1.595745 (-5525 3400);
PAINT GREEN (-5525 3400);
DISPLAY INVISIBLE (-5525 3400);
FORCEPROP 2 LAST CDS_LIB mstr_standard
J 0
(-5525 3450);
PAINT MONO (-5525 3450);
DISPLAY INVISIBLE (-5525 3450);
FORCEPROP 1 LAST PATH I61
J 0
(-5527 3450);
DISPLAY 0.872340 (-5527 3450);
PAINT GREEN (-5527 3450);
DISPLAY INVISIBLE (-5527 3450);
FORCEADD TAP..6
(-5525 3550);
FORCEPROP 3 LASTPIN (-5475 3550) SIG_NAME M_B_DQ<41>
J 0
(-5465 3560);
DISPLAY 0.659574 (-5465 3560);
PAINT MONO (-5465 3560);
DISPLAY INVISIBLE (-5465 3560);
FORCEPROP 1 LASTPIN (-5475 3550) BN 41
J 0
(-5527 3558);
DISPLAY 0.617021 (-5527 3558);
PAINT PINK (-5527 3558);
FORCEPROP 1 LAST HDL_TAP TRUE
J 0
(-5200 3425);
DISPLAY 1.595745 (-5200 3425);
PAINT GREEN (-5200 3425);
DISPLAY INVISIBLE (-5200 3425);
FORCEPROP 1 LAST BODY_TYPE PLUMBING
J 0
(-5525 3500);
DISPLAY 1.595745 (-5525 3500);
PAINT GREEN (-5525 3500);
DISPLAY INVISIBLE (-5525 3500);
FORCEPROP 2 LAST CDS_LIB mstr_standard
J 0
(-5525 3550);
PAINT MONO (-5525 3550);
DISPLAY INVISIBLE (-5525 3550);
FORCEPROP 1 LAST PATH I62
J 0
(-5527 3550);
DISPLAY 0.872340 (-5527 3550);
PAINT GREEN (-5527 3550);
DISPLAY INVISIBLE (-5527 3550);
FORCEADD TAP..6
(-5525 3500);
FORCEPROP 3 LASTPIN (-5475 3500) SIG_NAME M_B_DQ<40>
J 0
(-5465 3510);
DISPLAY 0.659574 (-5465 3510);
PAINT MONO (-5465 3510);
DISPLAY INVISIBLE (-5465 3510);
FORCEPROP 1 LASTPIN (-5475 3500) BN 40
J 0
(-5527 3508);
DISPLAY 0.617021 (-5527 3508);
PAINT PINK (-5527 3508);
FORCEPROP 1 LAST HDL_TAP TRUE
J 0
(-5200 3375);
DISPLAY 1.595745 (-5200 3375);
PAINT GREEN (-5200 3375);
DISPLAY INVISIBLE (-5200 3375);
FORCEPROP 1 LAST BODY_TYPE PLUMBING
J 0
(-5525 3450);
DISPLAY 1.595745 (-5525 3450);
PAINT GREEN (-5525 3450);
DISPLAY INVISIBLE (-5525 3450);
FORCEPROP 2 LAST CDS_LIB mstr_standard
J 0
(-5525 3500);
PAINT MONO (-5525 3500);
DISPLAY INVISIBLE (-5525 3500);
FORCEPROP 1 LAST PATH I63
J 0
(-5527 3500);
DISPLAY 0.872340 (-5527 3500);
PAINT GREEN (-5527 3500);
DISPLAY INVISIBLE (-5527 3500);
FORCEADD TAP..6
(-5525 3600);
FORCEPROP 3 LASTPIN (-5475 3600) SIG_NAME M_B_DQ<42>
J 0
(-5465 3610);
DISPLAY 0.659574 (-5465 3610);
PAINT MONO (-5465 3610);
DISPLAY INVISIBLE (-5465 3610);
FORCEPROP 1 LASTPIN (-5475 3600) BN 42
J 0
(-5527 3608);
DISPLAY 0.617021 (-5527 3608);
PAINT PINK (-5527 3608);
FORCEPROP 1 LAST HDL_TAP TRUE
J 0
(-5200 3475);
DISPLAY 1.595745 (-5200 3475);
PAINT GREEN (-5200 3475);
DISPLAY INVISIBLE (-5200 3475);
FORCEPROP 1 LAST BODY_TYPE PLUMBING
J 0
(-5525 3550);
DISPLAY 1.595745 (-5525 3550);
PAINT GREEN (-5525 3550);
DISPLAY INVISIBLE (-5525 3550);
FORCEPROP 2 LAST CDS_LIB mstr_standard
J 0
(-5525 3600);
PAINT MONO (-5525 3600);
DISPLAY INVISIBLE (-5525 3600);
FORCEPROP 1 LAST PATH I64
J 0
(-5527 3600);
DISPLAY 0.872340 (-5527 3600);
PAINT GREEN (-5527 3600);
DISPLAY INVISIBLE (-5527 3600);
FORCEADD TAP..6
(-5525 3650);
FORCEPROP 3 LASTPIN (-5475 3650) SIG_NAME M_B_DQ<43>
J 0
(-5465 3660);
DISPLAY 0.659574 (-5465 3660);
PAINT MONO (-5465 3660);
DISPLAY INVISIBLE (-5465 3660);
FORCEPROP 1 LASTPIN (-5475 3650) BN 43
J 0
(-5527 3658);
DISPLAY 0.617021 (-5527 3658);
PAINT PINK (-5527 3658);
FORCEPROP 1 LAST HDL_TAP TRUE
J 0
(-5200 3525);
DISPLAY 1.595745 (-5200 3525);
PAINT GREEN (-5200 3525);
DISPLAY INVISIBLE (-5200 3525);
FORCEPROP 1 LAST BODY_TYPE PLUMBING
J 0
(-5525 3600);
DISPLAY 1.595745 (-5525 3600);
PAINT GREEN (-5525 3600);
DISPLAY INVISIBLE (-5525 3600);
FORCEPROP 2 LAST CDS_LIB mstr_standard
J 0
(-5525 3650);
PAINT MONO (-5525 3650);
DISPLAY INVISIBLE (-5525 3650);
FORCEPROP 1 LAST PATH I65
J 0
(-5527 3650);
DISPLAY 0.872340 (-5527 3650);
PAINT GREEN (-5527 3650);
DISPLAY INVISIBLE (-5527 3650);
FORCEADD TAP..6
(-5525 3700);
FORCEPROP 3 LASTPIN (-5475 3700) SIG_NAME M_B_DQ<44>
J 0
(-5465 3710);
DISPLAY 0.659574 (-5465 3710);
PAINT MONO (-5465 3710);
DISPLAY INVISIBLE (-5465 3710);
FORCEPROP 1 LASTPIN (-5475 3700) BN 44
J 0
(-5527 3708);
DISPLAY 0.617021 (-5527 3708);
PAINT PINK (-5527 3708);
FORCEPROP 1 LAST HDL_TAP TRUE
J 0
(-5200 3575);
DISPLAY 1.595745 (-5200 3575);
PAINT GREEN (-5200 3575);
DISPLAY INVISIBLE (-5200 3575);
FORCEPROP 1 LAST BODY_TYPE PLUMBING
J 0
(-5525 3650);
DISPLAY 1.595745 (-5525 3650);
PAINT GREEN (-5525 3650);
DISPLAY INVISIBLE (-5525 3650);
FORCEPROP 2 LAST CDS_LIB mstr_standard
J 0
(-5525 3700);
PAINT MONO (-5525 3700);
DISPLAY INVISIBLE (-5525 3700);
FORCEPROP 1 LAST PATH I66
J 0
(-5527 3700);
DISPLAY 0.872340 (-5527 3700);
PAINT GREEN (-5527 3700);
DISPLAY INVISIBLE (-5527 3700);
FORCEADD TAP..6
(-5525 3750);
FORCEPROP 3 LASTPIN (-5475 3750) SIG_NAME M_B_DQ<45>
J 0
(-5465 3760);
DISPLAY 0.659574 (-5465 3760);
PAINT MONO (-5465 3760);
DISPLAY INVISIBLE (-5465 3760);
FORCEPROP 1 LASTPIN (-5475 3750) BN 45
J 0
(-5527 3758);
DISPLAY 0.617021 (-5527 3758);
PAINT PINK (-5527 3758);
FORCEPROP 1 LAST HDL_TAP TRUE
J 0
(-5200 3625);
DISPLAY 1.595745 (-5200 3625);
PAINT GREEN (-5200 3625);
DISPLAY INVISIBLE (-5200 3625);
FORCEPROP 1 LAST BODY_TYPE PLUMBING
J 0
(-5525 3700);
DISPLAY 1.595745 (-5525 3700);
PAINT GREEN (-5525 3700);
DISPLAY INVISIBLE (-5525 3700);
FORCEPROP 2 LAST CDS_LIB mstr_standard
J 0
(-5525 3750);
PAINT MONO (-5525 3750);
DISPLAY INVISIBLE (-5525 3750);
FORCEPROP 1 LAST PATH I67
J 0
(-5527 3750);
DISPLAY 0.872340 (-5527 3750);
PAINT GREEN (-5527 3750);
DISPLAY INVISIBLE (-5527 3750);
FORCEADD TAP..6
(-5525 3800);
FORCEPROP 3 LASTPIN (-5475 3800) SIG_NAME M_B_DQ<46>
J 0
(-5465 3810);
DISPLAY 0.659574 (-5465 3810);
PAINT MONO (-5465 3810);
DISPLAY INVISIBLE (-5465 3810);
FORCEPROP 1 LASTPIN (-5475 3800) BN 46
J 0
(-5527 3808);
DISPLAY 0.617021 (-5527 3808);
PAINT PINK (-5527 3808);
FORCEPROP 1 LAST HDL_TAP TRUE
J 0
(-5200 3675);
DISPLAY 1.595745 (-5200 3675);
PAINT GREEN (-5200 3675);
DISPLAY INVISIBLE (-5200 3675);
FORCEPROP 1 LAST BODY_TYPE PLUMBING
J 0
(-5525 3750);
DISPLAY 1.595745 (-5525 3750);
PAINT GREEN (-5525 3750);
DISPLAY INVISIBLE (-5525 3750);
FORCEPROP 2 LAST CDS_LIB mstr_standard
J 0
(-5525 3800);
PAINT MONO (-5525 3800);
DISPLAY INVISIBLE (-5525 3800);
FORCEPROP 1 LAST PATH I68
J 0
(-5527 3800);
DISPLAY 0.872340 (-5527 3800);
PAINT GREEN (-5527 3800);
DISPLAY INVISIBLE (-5527 3800);
FORCEADD TAP..6
(-5525 3850);
FORCEPROP 3 LASTPIN (-5475 3850) SIG_NAME M_B_DQ<47>
J 0
(-5465 3860);
DISPLAY 0.659574 (-5465 3860);
PAINT MONO (-5465 3860);
DISPLAY INVISIBLE (-5465 3860);
FORCEPROP 1 LASTPIN (-5475 3850) BN 47
J 0
(-5527 3858);
DISPLAY 0.617021 (-5527 3858);
PAINT PINK (-5527 3858);
FORCEPROP 1 LAST HDL_TAP TRUE
J 0
(-5200 3725);
DISPLAY 1.595745 (-5200 3725);
PAINT GREEN (-5200 3725);
DISPLAY INVISIBLE (-5200 3725);
FORCEPROP 1 LAST BODY_TYPE PLUMBING
J 0
(-5525 3800);
DISPLAY 1.595745 (-5525 3800);
PAINT GREEN (-5525 3800);
DISPLAY INVISIBLE (-5525 3800);
FORCEPROP 2 LAST CDS_LIB mstr_standard
J 0
(-5525 3850);
PAINT MONO (-5525 3850);
DISPLAY INVISIBLE (-5525 3850);
FORCEPROP 1 LAST PATH I69
J 0
(-5527 3850);
DISPLAY 0.872340 (-5527 3850);
PAINT GREEN (-5527 3850);
DISPLAY INVISIBLE (-5527 3850);
FORCEADD TAP..6
(-5525 700);
FORCEPROP 3 LASTPIN (-5475 700) SIG_NAME M_B_CLK_DN<2>
J 0
(-5465 710);
DISPLAY 0.659574 (-5465 710);
PAINT MONO (-5465 710);
DISPLAY INVISIBLE (-5465 710);
FORCEPROP 1 LASTPIN (-5475 700) BN 2
J 0
(-5527 708);
DISPLAY 0.617021 (-5527 708);
PAINT PINK (-5527 708);
FORCEPROP 1 LAST HDL_TAP TRUE
J 0
(-5200 575);
DISPLAY 1.595745 (-5200 575);
PAINT GREEN (-5200 575);
DISPLAY INVISIBLE (-5200 575);
FORCEPROP 1 LAST BODY_TYPE PLUMBING
J 0
(-5525 650);
DISPLAY 1.595745 (-5525 650);
PAINT GREEN (-5525 650);
DISPLAY INVISIBLE (-5525 650);
FORCEPROP 2 LAST CDS_LIB mstr_standard
J 0
(-5525 700);
PAINT MONO (-5525 700);
DISPLAY INVISIBLE (-5525 700);
FORCEPROP 1 LAST PATH I7
J 0
(-5527 700);
DISPLAY 0.872340 (-5527 700);
PAINT GREEN (-5527 700);
DISPLAY INVISIBLE (-5527 700);
FORCEADD TAP..6
(-5525 3900);
FORCEPROP 3 LASTPIN (-5475 3900) SIG_NAME M_B_DQ<48>
J 0
(-5465 3910);
DISPLAY 0.659574 (-5465 3910);
PAINT MONO (-5465 3910);
DISPLAY INVISIBLE (-5465 3910);
FORCEPROP 1 LASTPIN (-5475 3900) BN 48
J 0
(-5527 3908);
DISPLAY 0.617021 (-5527 3908);
PAINT PINK (-5527 3908);
FORCEPROP 1 LAST HDL_TAP TRUE
J 0
(-5200 3775);
DISPLAY 1.595745 (-5200 3775);
PAINT GREEN (-5200 3775);
DISPLAY INVISIBLE (-5200 3775);
FORCEPROP 1 LAST BODY_TYPE PLUMBING
J 0
(-5525 3850);
DISPLAY 1.595745 (-5525 3850);
PAINT GREEN (-5525 3850);
DISPLAY INVISIBLE (-5525 3850);
FORCEPROP 2 LAST CDS_LIB mstr_standard
J 0
(-5525 3900);
PAINT MONO (-5525 3900);
DISPLAY INVISIBLE (-5525 3900);
FORCEPROP 1 LAST PATH I70
J 0
(-5527 3900);
DISPLAY 0.872340 (-5527 3900);
PAINT GREEN (-5527 3900);
DISPLAY INVISIBLE (-5527 3900);
FORCEADD TAP..6
(-5525 3950);
FORCEPROP 3 LASTPIN (-5475 3950) SIG_NAME M_B_DQ<49>
J 0
(-5465 3960);
DISPLAY 0.659574 (-5465 3960);
PAINT MONO (-5465 3960);
DISPLAY INVISIBLE (-5465 3960);
FORCEPROP 1 LASTPIN (-5475 3950) BN 49
J 0
(-5527 3958);
DISPLAY 0.617021 (-5527 3958);
PAINT PINK (-5527 3958);
FORCEPROP 1 LAST HDL_TAP TRUE
J 0
(-5200 3825);
DISPLAY 1.595745 (-5200 3825);
PAINT GREEN (-5200 3825);
DISPLAY INVISIBLE (-5200 3825);
FORCEPROP 1 LAST BODY_TYPE PLUMBING
J 0
(-5525 3900);
DISPLAY 1.595745 (-5525 3900);
PAINT GREEN (-5525 3900);
DISPLAY INVISIBLE (-5525 3900);
FORCEPROP 2 LAST CDS_LIB mstr_standard
J 0
(-5525 3950);
PAINT MONO (-5525 3950);
DISPLAY INVISIBLE (-5525 3950);
FORCEPROP 1 LAST PATH I71
J 0
(-5527 3950);
DISPLAY 0.872340 (-5527 3950);
PAINT GREEN (-5527 3950);
DISPLAY INVISIBLE (-5527 3950);
FORCEADD OFFPAGE..6
(-6375 4775);
FORCEPROP 2 LAST $XR1 46 
J 0
(-6744 4775);
DISPLAY 0.638298 (-6744 4775);
PAINT MONO (-6744 4775);
FORCEPROP 2 LAST $XR0 45 
J 0
(-6654 4775);
DISPLAY 0.638298 (-6654 4775);
PAINT MONO (-6654 4775);
FORCEPROP 1 LAST COMMENT_BODY TRUE
J 0
(-6275 4700);
DISPLAY 1.170213 (-6275 4700);
PAINT GREEN (-6275 4700);
DISPLAY INVISIBLE (-6275 4700);
FORCEPROP 1 LAST OFFPAGE TRUE
J 0
(-6050 4650);
DISPLAY 1.170213 (-6050 4650);
PAINT GREEN (-6050 4650);
DISPLAY INVISIBLE (-6050 4650);
FORCEPROP 2 LAST CDS_LIB mstr_standard
J 0
(-6375 4775);
PAINT MONO (-6375 4775);
DISPLAY INVISIBLE (-6375 4775);
FORCEPROP 2 LAST PATH I72
J 0
(-6325 4850);
DISPLAY 1.021277 (-6325 4850);
PAINT ORANGE (-6325 4850);
DISPLAY INVISIBLE (-6325 4850);
FORCEADD TAP..6
(-5525 4050);
FORCEPROP 3 LASTPIN (-5475 4050) SIG_NAME M_B_DQ<51>
J 0
(-5465 4060);
DISPLAY 0.659574 (-5465 4060);
PAINT MONO (-5465 4060);
DISPLAY INVISIBLE (-5465 4060);
FORCEPROP 1 LASTPIN (-5475 4050) BN 51
J 0
(-5527 4058);
DISPLAY 0.617021 (-5527 4058);
PAINT PINK (-5527 4058);
FORCEPROP 1 LAST HDL_TAP TRUE
J 0
(-5200 3925);
DISPLAY 1.595745 (-5200 3925);
PAINT GREEN (-5200 3925);
DISPLAY INVISIBLE (-5200 3925);
FORCEPROP 1 LAST BODY_TYPE PLUMBING
J 0
(-5525 4000);
DISPLAY 1.595745 (-5525 4000);
PAINT GREEN (-5525 4000);
DISPLAY INVISIBLE (-5525 4000);
FORCEPROP 2 LAST CDS_LIB mstr_standard
J 0
(-5525 4050);
PAINT MONO (-5525 4050);
DISPLAY INVISIBLE (-5525 4050);
FORCEPROP 1 LAST PATH I73
J 0
(-5527 4050);
DISPLAY 0.872340 (-5527 4050);
PAINT GREEN (-5527 4050);
DISPLAY INVISIBLE (-5527 4050);
FORCEADD TAP..6
(-5525 4000);
FORCEPROP 3 LASTPIN (-5475 4000) SIG_NAME M_B_DQ<50>
J 0
(-5465 4010);
DISPLAY 0.659574 (-5465 4010);
PAINT MONO (-5465 4010);
DISPLAY INVISIBLE (-5465 4010);
FORCEPROP 1 LASTPIN (-5475 4000) BN 50
J 0
(-5527 4008);
DISPLAY 0.617021 (-5527 4008);
PAINT PINK (-5527 4008);
FORCEPROP 1 LAST HDL_TAP TRUE
J 0
(-5200 3875);
DISPLAY 1.595745 (-5200 3875);
PAINT GREEN (-5200 3875);
DISPLAY INVISIBLE (-5200 3875);
FORCEPROP 1 LAST BODY_TYPE PLUMBING
J 0
(-5525 3950);
DISPLAY 1.595745 (-5525 3950);
PAINT GREEN (-5525 3950);
DISPLAY INVISIBLE (-5525 3950);
FORCEPROP 2 LAST CDS_LIB mstr_standard
J 0
(-5525 4000);
PAINT MONO (-5525 4000);
DISPLAY INVISIBLE (-5525 4000);
FORCEPROP 1 LAST PATH I74
J 0
(-5527 4000);
DISPLAY 0.872340 (-5527 4000);
PAINT GREEN (-5527 4000);
DISPLAY INVISIBLE (-5527 4000);
FORCEADD TAP..6
(-5525 4150);
FORCEPROP 3 LASTPIN (-5475 4150) SIG_NAME M_B_DQ<53>
J 0
(-5465 4160);
DISPLAY 0.659574 (-5465 4160);
PAINT MONO (-5465 4160);
DISPLAY INVISIBLE (-5465 4160);
FORCEPROP 1 LASTPIN (-5475 4150) BN 53
J 0
(-5527 4158);
DISPLAY 0.617021 (-5527 4158);
PAINT PINK (-5527 4158);
FORCEPROP 1 LAST HDL_TAP TRUE
J 0
(-5200 4025);
DISPLAY 1.595745 (-5200 4025);
PAINT GREEN (-5200 4025);
DISPLAY INVISIBLE (-5200 4025);
FORCEPROP 1 LAST BODY_TYPE PLUMBING
J 0
(-5525 4100);
DISPLAY 1.595745 (-5525 4100);
PAINT GREEN (-5525 4100);
DISPLAY INVISIBLE (-5525 4100);
FORCEPROP 2 LAST CDS_LIB mstr_standard
J 0
(-5525 4150);
PAINT MONO (-5525 4150);
DISPLAY INVISIBLE (-5525 4150);
FORCEPROP 1 LAST PATH I75
J 0
(-5527 4150);
DISPLAY 0.872340 (-5527 4150);
PAINT GREEN (-5527 4150);
DISPLAY INVISIBLE (-5527 4150);
FORCEADD TAP..6
(-5525 4200);
FORCEPROP 3 LASTPIN (-5475 4200) SIG_NAME M_B_DQ<54>
J 0
(-5465 4210);
DISPLAY 0.659574 (-5465 4210);
PAINT MONO (-5465 4210);
DISPLAY INVISIBLE (-5465 4210);
FORCEPROP 1 LASTPIN (-5475 4200) BN 54
J 0
(-5527 4208);
DISPLAY 0.617021 (-5527 4208);
PAINT PINK (-5527 4208);
FORCEPROP 1 LAST HDL_TAP TRUE
J 0
(-5200 4075);
DISPLAY 1.595745 (-5200 4075);
PAINT GREEN (-5200 4075);
DISPLAY INVISIBLE (-5200 4075);
FORCEPROP 1 LAST BODY_TYPE PLUMBING
J 0
(-5525 4150);
DISPLAY 1.595745 (-5525 4150);
PAINT GREEN (-5525 4150);
DISPLAY INVISIBLE (-5525 4150);
FORCEPROP 2 LAST CDS_LIB mstr_standard
J 0
(-5525 4200);
PAINT MONO (-5525 4200);
DISPLAY INVISIBLE (-5525 4200);
FORCEPROP 1 LAST PATH I76
J 0
(-5527 4200);
DISPLAY 0.872340 (-5527 4200);
PAINT GREEN (-5527 4200);
DISPLAY INVISIBLE (-5527 4200);
FORCEADD TAP..6
(-5525 4100);
FORCEPROP 3 LASTPIN (-5475 4100) SIG_NAME M_B_DQ<52>
J 0
(-5465 4110);
DISPLAY 0.659574 (-5465 4110);
PAINT MONO (-5465 4110);
DISPLAY INVISIBLE (-5465 4110);
FORCEPROP 1 LASTPIN (-5475 4100) BN 52
J 0
(-5527 4108);
DISPLAY 0.617021 (-5527 4108);
PAINT PINK (-5527 4108);
FORCEPROP 1 LAST HDL_TAP TRUE
J 0
(-5200 3975);
DISPLAY 1.595745 (-5200 3975);
PAINT GREEN (-5200 3975);
DISPLAY INVISIBLE (-5200 3975);
FORCEPROP 1 LAST BODY_TYPE PLUMBING
J 0
(-5525 4050);
DISPLAY 1.595745 (-5525 4050);
PAINT GREEN (-5525 4050);
DISPLAY INVISIBLE (-5525 4050);
FORCEPROP 2 LAST CDS_LIB mstr_standard
J 0
(-5525 4100);
PAINT MONO (-5525 4100);
DISPLAY INVISIBLE (-5525 4100);
FORCEPROP 1 LAST PATH I77
J 0
(-5527 4100);
DISPLAY 0.872340 (-5527 4100);
PAINT GREEN (-5527 4100);
DISPLAY INVISIBLE (-5527 4100);
FORCEADD TAP..6
(-5525 4250);
FORCEPROP 3 LASTPIN (-5475 4250) SIG_NAME M_B_DQ<55>
J 0
(-5465 4260);
DISPLAY 0.659574 (-5465 4260);
PAINT MONO (-5465 4260);
DISPLAY INVISIBLE (-5465 4260);
FORCEPROP 1 LASTPIN (-5475 4250) BN 55
J 0
(-5527 4258);
DISPLAY 0.617021 (-5527 4258);
PAINT PINK (-5527 4258);
FORCEPROP 1 LAST HDL_TAP TRUE
J 0
(-5200 4125);
DISPLAY 1.595745 (-5200 4125);
PAINT GREEN (-5200 4125);
DISPLAY INVISIBLE (-5200 4125);
FORCEPROP 1 LAST BODY_TYPE PLUMBING
J 0
(-5525 4200);
DISPLAY 1.595745 (-5525 4200);
PAINT GREEN (-5525 4200);
DISPLAY INVISIBLE (-5525 4200);
FORCEPROP 2 LAST CDS_LIB mstr_standard
J 0
(-5525 4250);
PAINT MONO (-5525 4250);
DISPLAY INVISIBLE (-5525 4250);
FORCEPROP 1 LAST PATH I78
J 0
(-5527 4250);
DISPLAY 0.872340 (-5527 4250);
PAINT GREEN (-5527 4250);
DISPLAY INVISIBLE (-5527 4250);
FORCEADD TAP..6
(-5525 4300);
FORCEPROP 3 LASTPIN (-5475 4300) SIG_NAME M_B_DQ<56>
J 0
(-5465 4310);
DISPLAY 0.659574 (-5465 4310);
PAINT MONO (-5465 4310);
DISPLAY INVISIBLE (-5465 4310);
FORCEPROP 1 LASTPIN (-5475 4300) BN 56
J 0
(-5527 4308);
DISPLAY 0.617021 (-5527 4308);
PAINT PINK (-5527 4308);
FORCEPROP 1 LAST HDL_TAP TRUE
J 0
(-5200 4175);
DISPLAY 1.595745 (-5200 4175);
PAINT GREEN (-5200 4175);
DISPLAY INVISIBLE (-5200 4175);
FORCEPROP 1 LAST BODY_TYPE PLUMBING
J 0
(-5525 4250);
DISPLAY 1.595745 (-5525 4250);
PAINT GREEN (-5525 4250);
DISPLAY INVISIBLE (-5525 4250);
FORCEPROP 2 LAST CDS_LIB mstr_standard
J 0
(-5525 4300);
PAINT MONO (-5525 4300);
DISPLAY INVISIBLE (-5525 4300);
FORCEPROP 1 LAST PATH I79
J 0
(-5527 4300);
DISPLAY 0.872340 (-5527 4300);
PAINT GREEN (-5527 4300);
DISPLAY INVISIBLE (-5527 4300);
FORCEADD TAP..6
(-5525 800);
FORCEPROP 3 LASTPIN (-5475 800) SIG_NAME M_B_CLK_DP<0>
J 0
(-5465 810);
DISPLAY 0.659574 (-5465 810);
PAINT MONO (-5465 810);
DISPLAY INVISIBLE (-5465 810);
FORCEPROP 1 LASTPIN (-5475 800) BN 0
J 0
(-5527 808);
DISPLAY 0.617021 (-5527 808);
PAINT PINK (-5527 808);
FORCEPROP 1 LAST HDL_TAP TRUE
J 0
(-5200 675);
DISPLAY 1.595745 (-5200 675);
PAINT GREEN (-5200 675);
DISPLAY INVISIBLE (-5200 675);
FORCEPROP 1 LAST BODY_TYPE PLUMBING
J 0
(-5525 750);
DISPLAY 1.595745 (-5525 750);
PAINT GREEN (-5525 750);
DISPLAY INVISIBLE (-5525 750);
FORCEPROP 2 LAST CDS_LIB mstr_standard
J 0
(-5525 800);
PAINT MONO (-5525 800);
DISPLAY INVISIBLE (-5525 800);
FORCEPROP 1 LAST PATH I8
J 0
(-5527 800);
DISPLAY 0.872340 (-5527 800);
PAINT GREEN (-5527 800);
DISPLAY INVISIBLE (-5527 800);
FORCEADD TAP..6
(-5525 4350);
FORCEPROP 3 LASTPIN (-5475 4350) SIG_NAME M_B_DQ<57>
J 0
(-5465 4360);
DISPLAY 0.659574 (-5465 4360);
PAINT MONO (-5465 4360);
DISPLAY INVISIBLE (-5465 4360);
FORCEPROP 1 LASTPIN (-5475 4350) BN 57
J 0
(-5527 4358);
DISPLAY 0.617021 (-5527 4358);
PAINT PINK (-5527 4358);
FORCEPROP 1 LAST HDL_TAP TRUE
J 0
(-5200 4225);
DISPLAY 1.595745 (-5200 4225);
PAINT GREEN (-5200 4225);
DISPLAY INVISIBLE (-5200 4225);
FORCEPROP 1 LAST BODY_TYPE PLUMBING
J 0
(-5525 4300);
DISPLAY 1.595745 (-5525 4300);
PAINT GREEN (-5525 4300);
DISPLAY INVISIBLE (-5525 4300);
FORCEPROP 2 LAST CDS_LIB mstr_standard
J 0
(-5525 4350);
PAINT MONO (-5525 4350);
DISPLAY INVISIBLE (-5525 4350);
FORCEPROP 1 LAST PATH I80
J 0
(-5527 4350);
DISPLAY 0.872340 (-5527 4350);
PAINT GREEN (-5527 4350);
DISPLAY INVISIBLE (-5527 4350);
FORCEADD TAP..6
(-5525 4400);
FORCEPROP 3 LASTPIN (-5475 4400) SIG_NAME M_B_DQ<58>
J 0
(-5465 4410);
DISPLAY 0.659574 (-5465 4410);
PAINT MONO (-5465 4410);
DISPLAY INVISIBLE (-5465 4410);
FORCEPROP 1 LASTPIN (-5475 4400) BN 58
J 0
(-5527 4408);
DISPLAY 0.617021 (-5527 4408);
PAINT PINK (-5527 4408);
FORCEPROP 1 LAST HDL_TAP TRUE
J 0
(-5200 4275);
DISPLAY 1.595745 (-5200 4275);
PAINT GREEN (-5200 4275);
DISPLAY INVISIBLE (-5200 4275);
FORCEPROP 1 LAST BODY_TYPE PLUMBING
J 0
(-5525 4350);
DISPLAY 1.595745 (-5525 4350);
PAINT GREEN (-5525 4350);
DISPLAY INVISIBLE (-5525 4350);
FORCEPROP 2 LAST CDS_LIB mstr_standard
J 0
(-5525 4400);
PAINT MONO (-5525 4400);
DISPLAY INVISIBLE (-5525 4400);
FORCEPROP 1 LAST PATH I81
J 0
(-5527 4400);
DISPLAY 0.872340 (-5527 4400);
PAINT GREEN (-5527 4400);
DISPLAY INVISIBLE (-5527 4400);
FORCEADD TAP..6
(-5525 4450);
FORCEPROP 3 LASTPIN (-5475 4450) SIG_NAME M_B_DQ<59>
J 0
(-5465 4460);
DISPLAY 0.659574 (-5465 4460);
PAINT MONO (-5465 4460);
DISPLAY INVISIBLE (-5465 4460);
FORCEPROP 1 LASTPIN (-5475 4450) BN 59
J 0
(-5527 4458);
DISPLAY 0.617021 (-5527 4458);
PAINT PINK (-5527 4458);
FORCEPROP 1 LAST HDL_TAP TRUE
J 0
(-5200 4325);
DISPLAY 1.595745 (-5200 4325);
PAINT GREEN (-5200 4325);
DISPLAY INVISIBLE (-5200 4325);
FORCEPROP 1 LAST BODY_TYPE PLUMBING
J 0
(-5525 4400);
DISPLAY 1.595745 (-5525 4400);
PAINT GREEN (-5525 4400);
DISPLAY INVISIBLE (-5525 4400);
FORCEPROP 2 LAST CDS_LIB mstr_standard
J 0
(-5525 4450);
PAINT MONO (-5525 4450);
DISPLAY INVISIBLE (-5525 4450);
FORCEPROP 1 LAST PATH I82
J 0
(-5527 4450);
DISPLAY 0.872340 (-5527 4450);
PAINT GREEN (-5527 4450);
DISPLAY INVISIBLE (-5527 4450);
FORCEADD TAP..6
(-5525 4500);
FORCEPROP 3 LASTPIN (-5475 4500) SIG_NAME M_B_DQ<60>
J 0
(-5465 4510);
DISPLAY 0.659574 (-5465 4510);
PAINT MONO (-5465 4510);
DISPLAY INVISIBLE (-5465 4510);
FORCEPROP 1 LASTPIN (-5475 4500) BN 60
J 0
(-5527 4508);
DISPLAY 0.617021 (-5527 4508);
PAINT PINK (-5527 4508);
FORCEPROP 1 LAST HDL_TAP TRUE
J 0
(-5200 4375);
DISPLAY 1.595745 (-5200 4375);
PAINT GREEN (-5200 4375);
DISPLAY INVISIBLE (-5200 4375);
FORCEPROP 1 LAST BODY_TYPE PLUMBING
J 0
(-5525 4450);
DISPLAY 1.595745 (-5525 4450);
PAINT GREEN (-5525 4450);
DISPLAY INVISIBLE (-5525 4450);
FORCEPROP 2 LAST CDS_LIB mstr_standard
J 0
(-5525 4500);
PAINT MONO (-5525 4500);
DISPLAY INVISIBLE (-5525 4500);
FORCEPROP 1 LAST PATH I83
J 0
(-5527 4500);
DISPLAY 0.872340 (-5527 4500);
PAINT GREEN (-5527 4500);
DISPLAY INVISIBLE (-5527 4500);
FORCEADD TAP..6
(-5525 4550);
FORCEPROP 3 LASTPIN (-5475 4550) SIG_NAME M_B_DQ<61>
J 0
(-5465 4560);
DISPLAY 0.659574 (-5465 4560);
PAINT MONO (-5465 4560);
DISPLAY INVISIBLE (-5465 4560);
FORCEPROP 1 LASTPIN (-5475 4550) BN 61
J 0
(-5527 4558);
DISPLAY 0.617021 (-5527 4558);
PAINT PINK (-5527 4558);
FORCEPROP 1 LAST HDL_TAP TRUE
J 0
(-5200 4425);
DISPLAY 1.595745 (-5200 4425);
PAINT GREEN (-5200 4425);
DISPLAY INVISIBLE (-5200 4425);
FORCEPROP 1 LAST BODY_TYPE PLUMBING
J 0
(-5525 4500);
DISPLAY 1.595745 (-5525 4500);
PAINT GREEN (-5525 4500);
DISPLAY INVISIBLE (-5525 4500);
FORCEPROP 2 LAST CDS_LIB mstr_standard
J 0
(-5525 4550);
PAINT MONO (-5525 4550);
DISPLAY INVISIBLE (-5525 4550);
FORCEPROP 1 LAST PATH I84
J 0
(-5527 4550);
DISPLAY 0.872340 (-5527 4550);
PAINT GREEN (-5527 4550);
DISPLAY INVISIBLE (-5527 4550);
FORCEADD TAP..6
(-5525 4650);
FORCEPROP 3 LASTPIN (-5475 4650) SIG_NAME M_B_DQ<63>
J 0
(-5465 4660);
DISPLAY 0.659574 (-5465 4660);
PAINT MONO (-5465 4660);
DISPLAY INVISIBLE (-5465 4660);
FORCEPROP 1 LASTPIN (-5475 4650) BN 63
J 0
(-5527 4658);
DISPLAY 0.617021 (-5527 4658);
PAINT PINK (-5527 4658);
FORCEPROP 1 LAST HDL_TAP TRUE
J 0
(-5200 4525);
DISPLAY 1.595745 (-5200 4525);
PAINT GREEN (-5200 4525);
DISPLAY INVISIBLE (-5200 4525);
FORCEPROP 1 LAST BODY_TYPE PLUMBING
J 0
(-5525 4600);
DISPLAY 1.595745 (-5525 4600);
PAINT GREEN (-5525 4600);
DISPLAY INVISIBLE (-5525 4600);
FORCEPROP 2 LAST CDS_LIB mstr_standard
J 0
(-5525 4650);
PAINT MONO (-5525 4650);
DISPLAY INVISIBLE (-5525 4650);
FORCEPROP 1 LAST PATH I85
J 0
(-5527 4650);
DISPLAY 0.872340 (-5527 4650);
PAINT GREEN (-5527 4650);
DISPLAY INVISIBLE (-5527 4650);
FORCEADD TAP..6
(-5525 4600);
FORCEPROP 3 LASTPIN (-5475 4600) SIG_NAME M_B_DQ<62>
J 0
(-5465 4610);
DISPLAY 0.659574 (-5465 4610);
PAINT MONO (-5465 4610);
DISPLAY INVISIBLE (-5465 4610);
FORCEPROP 1 LASTPIN (-5475 4600) BN 62
J 0
(-5527 4608);
DISPLAY 0.617021 (-5527 4608);
PAINT PINK (-5527 4608);
FORCEPROP 1 LAST HDL_TAP TRUE
J 0
(-5200 4475);
DISPLAY 1.595745 (-5200 4475);
PAINT GREEN (-5200 4475);
DISPLAY INVISIBLE (-5200 4475);
FORCEPROP 1 LAST BODY_TYPE PLUMBING
J 0
(-5525 4550);
DISPLAY 1.595745 (-5525 4550);
PAINT GREEN (-5525 4550);
DISPLAY INVISIBLE (-5525 4550);
FORCEPROP 2 LAST CDS_LIB mstr_standard
J 0
(-5525 4600);
PAINT MONO (-5525 4600);
DISPLAY INVISIBLE (-5525 4600);
FORCEPROP 1 LAST PATH I86
J 0
(-5527 4600);
DISPLAY 0.872340 (-5527 4600);
PAINT GREEN (-5527 4600);
DISPLAY INVISIBLE (-5527 4600);
FORCEADD TAP..6
R 2
(-2800 800);
FORCEPROP 3 LASTPIN (-2850 800) SIG_NAME M_B_BG<0>
J 0
(-2840 810);
DISPLAY 0.659574 (-2840 810);
PAINT MONO (-2840 810);
DISPLAY INVISIBLE (-2840 810);
FORCEPROP 1 LASTPIN (-2850 800) BN 0
J 2
(-2798 808);
DISPLAY 0.617021 (-2798 808);
PAINT PINK (-2798 808);
FORCEPROP 1 LAST HDL_TAP TRUE
J 2
(-3125 675);
DISPLAY 1.595745 (-3125 675);
PAINT GREEN (-3125 675);
DISPLAY INVISIBLE (-3125 675);
FORCEPROP 1 LAST BODY_TYPE PLUMBING
J 2
(-2800 750);
DISPLAY 1.595745 (-2800 750);
PAINT GREEN (-2800 750);
DISPLAY INVISIBLE (-2800 750);
FORCEPROP 2 LAST CDS_LIB mstr_standard
J 0
(-2800 800);
PAINT MONO (-2800 800);
DISPLAY INVISIBLE (-2800 800);
FORCEPROP 1 LAST PATH I87
J 2
(-2798 800);
DISPLAY 0.872340 (-2798 800);
PAINT GREEN (-2798 800);
DISPLAY INVISIBLE (-2798 800);
FORCEADD TAP..6
R 2
(-2800 850);
FORCEPROP 3 LASTPIN (-2850 850) SIG_NAME M_B_BG<1>
J 0
(-2840 860);
DISPLAY 0.659574 (-2840 860);
PAINT MONO (-2840 860);
DISPLAY INVISIBLE (-2840 860);
FORCEPROP 1 LASTPIN (-2850 850) BN 1
J 2
(-2798 858);
DISPLAY 0.617021 (-2798 858);
PAINT PINK (-2798 858);
FORCEPROP 1 LAST HDL_TAP TRUE
J 2
(-3125 725);
DISPLAY 1.595745 (-3125 725);
PAINT GREEN (-3125 725);
DISPLAY INVISIBLE (-3125 725);
FORCEPROP 1 LAST BODY_TYPE PLUMBING
J 2
(-2800 800);
DISPLAY 1.595745 (-2800 800);
PAINT GREEN (-2800 800);
DISPLAY INVISIBLE (-2800 800);
FORCEPROP 2 LAST CDS_LIB mstr_standard
J 0
(-2800 850);
PAINT MONO (-2800 850);
DISPLAY INVISIBLE (-2800 850);
FORCEPROP 1 LAST PATH I88
J 2
(-2798 850);
DISPLAY 0.872340 (-2798 850);
PAINT GREEN (-2798 850);
DISPLAY INVISIBLE (-2798 850);
FORCEADD TAP..6
R 2
(-2800 750);
FORCEPROP 3 LASTPIN (-2850 750) SIG_NAME M_B_BA<1>
J 0
(-2840 760);
DISPLAY 0.659574 (-2840 760);
PAINT MONO (-2840 760);
DISPLAY INVISIBLE (-2840 760);
FORCEPROP 1 LASTPIN (-2850 750) BN 1
J 2
(-2798 758);
DISPLAY 0.617021 (-2798 758);
PAINT PINK (-2798 758);
FORCEPROP 1 LAST HDL_TAP TRUE
J 2
(-3125 625);
DISPLAY 1.595745 (-3125 625);
PAINT GREEN (-3125 625);
DISPLAY INVISIBLE (-3125 625);
FORCEPROP 1 LAST BODY_TYPE PLUMBING
J 2
(-2800 700);
DISPLAY 1.595745 (-2800 700);
PAINT GREEN (-2800 700);
DISPLAY INVISIBLE (-2800 700);
FORCEPROP 2 LAST CDS_LIB mstr_standard
J 0
(-2800 750);
PAINT MONO (-2800 750);
DISPLAY INVISIBLE (-2800 750);
FORCEPROP 1 LAST PATH I89
J 2
(-2798 750);
DISPLAY 0.872340 (-2798 750);
PAINT GREEN (-2798 750);
DISPLAY INVISIBLE (-2798 750);
FORCEADD TAP..6
(-5525 850);
FORCEPROP 3 LASTPIN (-5475 850) SIG_NAME M_B_CLK_DP<1>
J 0
(-5465 860);
DISPLAY 0.659574 (-5465 860);
PAINT MONO (-5465 860);
DISPLAY INVISIBLE (-5465 860);
FORCEPROP 1 LASTPIN (-5475 850) BN 1
J 0
(-5527 858);
DISPLAY 0.617021 (-5527 858);
PAINT PINK (-5527 858);
FORCEPROP 1 LAST HDL_TAP TRUE
J 0
(-5200 725);
DISPLAY 1.595745 (-5200 725);
PAINT GREEN (-5200 725);
DISPLAY INVISIBLE (-5200 725);
FORCEPROP 1 LAST BODY_TYPE PLUMBING
J 0
(-5525 800);
DISPLAY 1.595745 (-5525 800);
PAINT GREEN (-5525 800);
DISPLAY INVISIBLE (-5525 800);
FORCEPROP 2 LAST CDS_LIB mstr_standard
J 0
(-5525 850);
PAINT MONO (-5525 850);
DISPLAY INVISIBLE (-5525 850);
FORCEPROP 1 LAST PATH I9
J 0
(-5527 850);
DISPLAY 0.872340 (-5527 850);
PAINT GREEN (-5527 850);
DISPLAY INVISIBLE (-5527 850);
FORCEADD TAP..6
R 2
(-2800 700);
FORCEPROP 3 LASTPIN (-2850 700) SIG_NAME M_B_BA<0>
J 0
(-2840 710);
DISPLAY 0.659574 (-2840 710);
PAINT MONO (-2840 710);
DISPLAY INVISIBLE (-2840 710);
FORCEPROP 1 LASTPIN (-2850 700) BN 0
J 2
(-2798 708);
DISPLAY 0.617021 (-2798 708);
PAINT PINK (-2798 708);
FORCEPROP 1 LAST HDL_TAP TRUE
J 2
(-3125 575);
DISPLAY 1.595745 (-3125 575);
PAINT GREEN (-3125 575);
DISPLAY INVISIBLE (-3125 575);
FORCEPROP 1 LAST BODY_TYPE PLUMBING
J 2
(-2800 650);
DISPLAY 1.595745 (-2800 650);
PAINT GREEN (-2800 650);
DISPLAY INVISIBLE (-2800 650);
FORCEPROP 2 LAST CDS_LIB mstr_standard
J 0
(-2800 700);
PAINT MONO (-2800 700);
DISPLAY INVISIBLE (-2800 700);
FORCEPROP 1 LAST PATH I90
J 2
(-2798 700);
DISPLAY 0.872340 (-2798 700);
PAINT GREEN (-2798 700);
DISPLAY INVISIBLE (-2798 700);
FORCEADD TAP..6
R 2
(-2800 950);
FORCEPROP 3 LASTPIN (-2850 950) SIG_NAME M_B_CS_N<0>
J 0
(-2840 960);
DISPLAY 0.659574 (-2840 960);
PAINT MONO (-2840 960);
DISPLAY INVISIBLE (-2840 960);
FORCEPROP 1 LASTPIN (-2850 950) BN 0
J 2
(-2798 958);
DISPLAY 0.617021 (-2798 958);
PAINT PINK (-2798 958);
FORCEPROP 1 LAST HDL_TAP TRUE
J 2
(-3125 825);
DISPLAY 1.595745 (-3125 825);
PAINT GREEN (-3125 825);
DISPLAY INVISIBLE (-3125 825);
FORCEPROP 1 LAST BODY_TYPE PLUMBING
J 2
(-2800 900);
DISPLAY 1.595745 (-2800 900);
PAINT GREEN (-2800 900);
DISPLAY INVISIBLE (-2800 900);
FORCEPROP 2 LAST CDS_LIB mstr_standard
J 0
(-2800 950);
PAINT MONO (-2800 950);
DISPLAY INVISIBLE (-2800 950);
FORCEPROP 1 LAST PATH I91
J 2
(-2798 950);
DISPLAY 0.872340 (-2798 950);
PAINT GREEN (-2798 950);
DISPLAY INVISIBLE (-2798 950);
FORCEADD TAP..6
R 2
(-2800 1150);
FORCEPROP 3 LASTPIN (-2850 1150) SIG_NAME M_B_CS_N<4>
J 0
(-2840 1160);
DISPLAY 0.659574 (-2840 1160);
PAINT MONO (-2840 1160);
DISPLAY INVISIBLE (-2840 1160);
FORCEPROP 1 LASTPIN (-2850 1150) BN 4
J 2
(-2798 1158);
DISPLAY 0.617021 (-2798 1158);
PAINT PINK (-2798 1158);
FORCEPROP 1 LAST HDL_TAP TRUE
J 2
(-3125 1025);
DISPLAY 1.595745 (-3125 1025);
PAINT GREEN (-3125 1025);
DISPLAY INVISIBLE (-3125 1025);
FORCEPROP 1 LAST BODY_TYPE PLUMBING
J 2
(-2800 1100);
DISPLAY 1.595745 (-2800 1100);
PAINT GREEN (-2800 1100);
DISPLAY INVISIBLE (-2800 1100);
FORCEPROP 2 LAST CDS_LIB mstr_standard
J 0
(-2800 1150);
PAINT MONO (-2800 1150);
DISPLAY INVISIBLE (-2800 1150);
FORCEPROP 1 LAST PATH I92
J 2
(-2798 1150);
DISPLAY 0.872340 (-2798 1150);
PAINT GREEN (-2798 1150);
DISPLAY INVISIBLE (-2798 1150);
FORCEADD TAP..6
R 2
(-2800 1100);
FORCEPROP 3 LASTPIN (-2850 1100) SIG_NAME M_B_CS_N<3>
J 0
(-2840 1110);
DISPLAY 0.659574 (-2840 1110);
PAINT MONO (-2840 1110);
DISPLAY INVISIBLE (-2840 1110);
FORCEPROP 1 LASTPIN (-2850 1100) BN 3
J 2
(-2798 1108);
DISPLAY 0.617021 (-2798 1108);
PAINT PINK (-2798 1108);
FORCEPROP 1 LAST HDL_TAP TRUE
J 2
(-3125 975);
DISPLAY 1.595745 (-3125 975);
PAINT GREEN (-3125 975);
DISPLAY INVISIBLE (-3125 975);
FORCEPROP 1 LAST BODY_TYPE PLUMBING
J 2
(-2800 1050);
DISPLAY 1.595745 (-2800 1050);
PAINT GREEN (-2800 1050);
DISPLAY INVISIBLE (-2800 1050);
FORCEPROP 2 LAST CDS_LIB mstr_standard
J 0
(-2800 1100);
PAINT MONO (-2800 1100);
DISPLAY INVISIBLE (-2800 1100);
FORCEPROP 1 LAST PATH I93
J 2
(-2798 1100);
DISPLAY 0.872340 (-2798 1100);
PAINT GREEN (-2798 1100);
DISPLAY INVISIBLE (-2798 1100);
FORCEADD TAP..6
R 2
(-2800 1050);
FORCEPROP 3 LASTPIN (-2850 1050) SIG_NAME M_B_CS_N<2>
J 0
(-2840 1060);
DISPLAY 0.659574 (-2840 1060);
PAINT MONO (-2840 1060);
DISPLAY INVISIBLE (-2840 1060);
FORCEPROP 1 LASTPIN (-2850 1050) BN 2
J 2
(-2798 1058);
DISPLAY 0.617021 (-2798 1058);
PAINT PINK (-2798 1058);
FORCEPROP 1 LAST HDL_TAP TRUE
J 2
(-3125 925);
DISPLAY 1.595745 (-3125 925);
PAINT GREEN (-3125 925);
DISPLAY INVISIBLE (-3125 925);
FORCEPROP 1 LAST BODY_TYPE PLUMBING
J 2
(-2800 1000);
DISPLAY 1.595745 (-2800 1000);
PAINT GREEN (-2800 1000);
DISPLAY INVISIBLE (-2800 1000);
FORCEPROP 2 LAST CDS_LIB mstr_standard
J 0
(-2800 1050);
PAINT MONO (-2800 1050);
DISPLAY INVISIBLE (-2800 1050);
FORCEPROP 1 LAST PATH I94
J 2
(-2798 1050);
DISPLAY 0.872340 (-2798 1050);
PAINT GREEN (-2798 1050);
DISPLAY INVISIBLE (-2798 1050);
FORCEADD TAP..6
R 2
(-2800 1000);
FORCEPROP 3 LASTPIN (-2850 1000) SIG_NAME M_B_CS_N<1>
J 0
(-2840 1010);
DISPLAY 0.659574 (-2840 1010);
PAINT MONO (-2840 1010);
DISPLAY INVISIBLE (-2840 1010);
FORCEPROP 1 LASTPIN (-2850 1000) BN 1
J 2
(-2798 1008);
DISPLAY 0.617021 (-2798 1008);
PAINT PINK (-2798 1008);
FORCEPROP 1 LAST HDL_TAP TRUE
J 2
(-3125 875);
DISPLAY 1.595745 (-3125 875);
PAINT GREEN (-3125 875);
DISPLAY INVISIBLE (-3125 875);
FORCEPROP 1 LAST BODY_TYPE PLUMBING
J 2
(-2800 950);
DISPLAY 1.595745 (-2800 950);
PAINT GREEN (-2800 950);
DISPLAY INVISIBLE (-2800 950);
FORCEPROP 2 LAST CDS_LIB mstr_standard
J 0
(-2800 1000);
PAINT MONO (-2800 1000);
DISPLAY INVISIBLE (-2800 1000);
FORCEPROP 1 LAST PATH I95
J 2
(-2798 1000);
DISPLAY 0.872340 (-2798 1000);
PAINT GREEN (-2798 1000);
DISPLAY INVISIBLE (-2798 1000);
FORCEADD TAP..6
R 2
(-2800 1400);
FORCEPROP 3 LASTPIN (-2850 1400) SIG_NAME M_B_ODT<0>
J 0
(-2840 1410);
DISPLAY 0.659574 (-2840 1410);
PAINT MONO (-2840 1410);
DISPLAY INVISIBLE (-2840 1410);
FORCEPROP 1 LASTPIN (-2850 1400) BN 0
J 2
(-2798 1408);
DISPLAY 0.617021 (-2798 1408);
PAINT PINK (-2798 1408);
FORCEPROP 1 LAST HDL_TAP TRUE
J 2
(-3125 1275);
DISPLAY 1.595745 (-3125 1275);
PAINT GREEN (-3125 1275);
DISPLAY INVISIBLE (-3125 1275);
FORCEPROP 1 LAST BODY_TYPE PLUMBING
J 2
(-2800 1350);
DISPLAY 1.595745 (-2800 1350);
PAINT GREEN (-2800 1350);
DISPLAY INVISIBLE (-2800 1350);
FORCEPROP 2 LAST CDS_LIB mstr_standard
J 0
(-2800 1400);
PAINT MONO (-2800 1400);
DISPLAY INVISIBLE (-2800 1400);
FORCEPROP 1 LAST PATH I96
J 2
(-2798 1400);
DISPLAY 0.872340 (-2798 1400);
PAINT GREEN (-2798 1400);
DISPLAY INVISIBLE (-2798 1400);
FORCEADD TAP..6
R 2
(-2800 1250);
FORCEPROP 3 LASTPIN (-2850 1250) SIG_NAME M_B_CS_N<6>
J 0
(-2840 1260);
DISPLAY 0.659574 (-2840 1260);
PAINT MONO (-2840 1260);
DISPLAY INVISIBLE (-2840 1260);
FORCEPROP 1 LASTPIN (-2850 1250) BN 6
J 2
(-2798 1258);
DISPLAY 0.617021 (-2798 1258);
PAINT PINK (-2798 1258);
FORCEPROP 1 LAST HDL_TAP TRUE
J 2
(-3125 1125);
DISPLAY 1.595745 (-3125 1125);
PAINT GREEN (-3125 1125);
DISPLAY INVISIBLE (-3125 1125);
FORCEPROP 1 LAST BODY_TYPE PLUMBING
J 2
(-2800 1200);
DISPLAY 1.595745 (-2800 1200);
PAINT GREEN (-2800 1200);
DISPLAY INVISIBLE (-2800 1200);
FORCEPROP 2 LAST CDS_LIB mstr_standard
J 0
(-2800 1250);
PAINT MONO (-2800 1250);
DISPLAY INVISIBLE (-2800 1250);
FORCEPROP 1 LAST PATH I97
J 2
(-2798 1250);
DISPLAY 0.872340 (-2798 1250);
PAINT GREEN (-2798 1250);
DISPLAY INVISIBLE (-2798 1250);
FORCEADD TAP..6
R 2
(-2800 1200);
FORCEPROP 3 LASTPIN (-2850 1200) SIG_NAME M_B_CS_N<5>
J 0
(-2840 1210);
DISPLAY 0.659574 (-2840 1210);
PAINT MONO (-2840 1210);
DISPLAY INVISIBLE (-2840 1210);
FORCEPROP 1 LASTPIN (-2850 1200) BN 5
J 2
(-2798 1208);
DISPLAY 0.617021 (-2798 1208);
PAINT PINK (-2798 1208);
FORCEPROP 1 LAST HDL_TAP TRUE
J 2
(-3125 1075);
DISPLAY 1.595745 (-3125 1075);
PAINT GREEN (-3125 1075);
DISPLAY INVISIBLE (-3125 1075);
FORCEPROP 1 LAST BODY_TYPE PLUMBING
J 2
(-2800 1150);
DISPLAY 1.595745 (-2800 1150);
PAINT GREEN (-2800 1150);
DISPLAY INVISIBLE (-2800 1150);
FORCEPROP 2 LAST CDS_LIB mstr_standard
J 0
(-2800 1200);
PAINT MONO (-2800 1200);
DISPLAY INVISIBLE (-2800 1200);
FORCEPROP 1 LAST PATH I98
J 2
(-2798 1200);
DISPLAY 0.872340 (-2798 1200);
PAINT GREEN (-2798 1200);
DISPLAY INVISIBLE (-2798 1200);
FORCEADD TAP..6
R 2
(-2800 1300);
FORCEPROP 3 LASTPIN (-2850 1300) SIG_NAME M_B_CS_N<7>
J 0
(-2840 1310);
DISPLAY 0.659574 (-2840 1310);
PAINT MONO (-2840 1310);
DISPLAY INVISIBLE (-2840 1310);
FORCEPROP 1 LASTPIN (-2850 1300) BN 7
J 2
(-2798 1308);
DISPLAY 0.617021 (-2798 1308);
PAINT PINK (-2798 1308);
FORCEPROP 1 LAST HDL_TAP TRUE
J 2
(-3125 1175);
DISPLAY 1.595745 (-3125 1175);
PAINT GREEN (-3125 1175);
DISPLAY INVISIBLE (-3125 1175);
FORCEPROP 1 LAST BODY_TYPE PLUMBING
J 2
(-2800 1250);
DISPLAY 1.595745 (-2800 1250);
PAINT GREEN (-2800 1250);
DISPLAY INVISIBLE (-2800 1250);
FORCEPROP 2 LAST CDS_LIB mstr_standard
J 0
(-2800 1300);
PAINT MONO (-2800 1300);
DISPLAY INVISIBLE (-2800 1300);
FORCEPROP 1 LAST PATH I99
J 2
(-2798 1300);
DISPLAY 0.872340 (-2798 1300);
PAINT GREEN (-2798 1300);
DISPLAY INVISIBLE (-2798 1300);
FORCEADD INTEL_CORP_BPAGE..1
(0 0);
FORCEPROP 1 LAST CDS_CON_LAST_MODIFIED Fri Jun 16 17:48:10 2017
J 0
(-1425 325);
DISPLAY 1.340426 (-1425 325);
PAINT GREEN (-1425 325);
DISPLAY INVISIBLE (-1425 325);
FORCEPROP 1 LAST CUSTOM_TXT_CDS <CURRENT_DESIGN_SHEET> OF <TOTAL_DESIGN_SHEETS>
J 0
(-500 25);
PAINT ORANGE (-500 25);
FORCEPROP 1 LAST CUSTOM_TXT_CDS <CON_LAST_MODIFIED>
J 0
(-4000 100);
PAINT ORANGE (-4000 100);
FORCEPROP 2 LAST CUSTOM_TXT_CDS <XR_PAGE_TITLE>
J 0
(-7890 5250);
DISPLAY 0.638298 (-7890 5250);
PAINT PINK (-7890 5250);
DISPLAY INVISIBLE (-7890 5250);
FORCEPROP 1 LAST SCH_TITLE SKYLAKE - SKT0 - 4 OF 21
J 0
(-7950 50);
DISPLAY 1.212766 (-7950 50);
PAINT GREEN (-7950 50);
FORCEPROP 1 LAST COMMENT_BODY TRUE
J 0
(12 12);
DISPLAY 0.638298 (12 12);
PAINT GREEN (12 12);
DISPLAY INVISIBLE (12 12);
FORCEPROP 2 LAST PAGE_BORDER TRUE
J 0
(-7890 5250);
DISPLAY 0.851064 (-7890 5250);
PAINT PINK (-7890 5250);
DISPLAY INVISIBLE (-7890 5250);
FORCEPROP 2 LAST CDS_LIB mstr_symbols
J 0
(0 0);
PAINT ORANGE (0 0);
DISPLAY INVISIBLE (0 0);
FORCEPROP 2 LAST CDS_XR_PAGE_TITLE CR-24 : @BASEBOARD_FAB2_LIB.BASEBOARD_FAB2(SCH_1):PAGE24
J 0
(-7890 5250);
DISPLAY 0.638298 (-7890 5250);
PAINT PINK (-7890 5250);
DISPLAY INVISIBLE (-7890 5250);
FORCEADD DESIGN_NOTE..1
(-6375 375);
FORCEPROP 0 LAST L1 CPU SYMBOLS 1-30 ARE PRELIMINARY AND SUBJECT TO CHANGE
J 0
(-6575 250);
DISPLAY 1.021277 (-6575 250);
PAINT ORANGE (-6575 250);
FORCEPROP 1 LAST COMMENT_BODY TRUE
J 0
(-6350 475);
DISPLAY 0.978723 (-6350 475);
PAINT ORANGE (-6350 475);
DISPLAY INVISIBLE (-6350 475);
FORCEPROP 2 LAST CDS_LIB mstr_symbols
J 0
(-6375 375);
PAINT ORANGE (-6375 375);
DISPLAY INVISIBLE (-6375 375);
FORCEADD PRELIM..10
(-4165 2540);
PAINT GRAY (-4165 2540);
FORCEPROP 1 LAST COMMENT_BODY TRUE
J 0
(-4165 2540);
PAINT ORANGE (-4165 2540);
DISPLAY INVISIBLE (-4165 2540);
FORCEPROP 2 LAST CDS_LIB mstr_misc
J 0
(-4165 2540);
PAINT ORANGE (-4165 2540);
DISPLAY INVISIBLE (-4165 2540);
WIRE 17 -1 (-2000 4725)(-2750 4725);
FORCEPROP 2 LAST SIG_NAME M_B_DQS_DP<17:0>
J 0
(-2650 4735);
DISPLAY 0.617021 (-2650 4735);
PAINT ORANGE (-2650 4735);
WIRE 17 -1 (-2750 4675)(-2750 4725);
WIRE 17 -1 (-2750 4625)(-2750 4675);
WIRE 17 -1 (-2750 4575)(-2750 4625);
WIRE 17 -1 (-2750 4525)(-2750 4575);
WIRE 17 -1 (-2750 4475)(-2750 4525);
WIRE 17 -1 (-2750 4425)(-2750 4475);
WIRE 17 -1 (-2750 4375)(-2750 4425);
WIRE 17 -1 (-2750 4325)(-2750 4375);
WIRE 17 -1 (-2750 3825)(-2750 3875);
WIRE 17 -1 (-2750 3875)(-2750 3925);
WIRE 17 -1 (-2750 4275)(-2750 4325);
WIRE 17 -1 (-2750 4225)(-2750 4275);
WIRE 17 -1 (-2750 3925)(-2750 3975);
WIRE 17 -1 (-2750 3975)(-2750 4025);
WIRE 17 -1 (-2750 4175)(-2750 4225);
WIRE 17 -1 (-2750 4125)(-2750 4175);
WIRE 17 -1 (-2750 4025)(-2750 4075);
WIRE 17 -1 (-2750 4075)(-2750 4125);
WIRE 17 -1 (-2000 2800)(-2750 2800);
FORCEPROP 2 LAST SIG_NAME M_B_MA<17:0>
J 0
(-2650 2810);
DISPLAY 0.617021 (-2650 2810);
PAINT ORANGE (-2650 2810);
WIRE 17 -1 (-2750 2775)(-2750 2800);
WIRE 17 -1 (-2750 2725)(-2750 2775);
WIRE 17 -1 (-2750 2675)(-2750 2725);
WIRE 17 -1 (-2750 2625)(-2750 2675);
WIRE 17 -1 (-2750 2575)(-2750 2625);
WIRE 17 -1 (-2750 2525)(-2750 2575);
WIRE 17 -1 (-2750 2475)(-2750 2525);
WIRE 17 -1 (-2750 2425)(-2750 2475);
WIRE 17 -1 (-2750 2375)(-2750 2425);
WIRE 17 -1 (-2750 2325)(-2750 2375);
WIRE 17 -1 (-2750 2275)(-2750 2325);
WIRE 17 -1 (-2750 2225)(-2750 2275);
WIRE 17 -1 (-2750 2175)(-2750 2225);
WIRE 17 -1 (-2750 1925)(-2750 1975);
WIRE 17 -1 (-2750 2125)(-2750 2175);
WIRE 17 -1 (-2750 2075)(-2750 2125);
WIRE 17 -1 (-2750 1975)(-2750 2025);
WIRE 17 -1 (-2750 2025)(-2750 2075);
WIRE 17 -1 (-2000 3750)(-2750 3750);
FORCEPROP 2 LAST SIG_NAME M_B_DQS_DN<17:0>
J 0
(-2650 3760);
DISPLAY 0.617021 (-2650 3760);
PAINT ORANGE (-2650 3760);
WIRE 17 -1 (-2750 3725)(-2750 3750);
WIRE 17 -1 (-2750 3675)(-2750 3725);
WIRE 17 -1 (-2750 3625)(-2750 3675);
WIRE 17 -1 (-2750 3575)(-2750 3625);
WIRE 17 -1 (-2750 3525)(-2750 3575);
WIRE 17 -1 (-2750 3475)(-2750 3525);
WIRE 17 -1 (-2750 3425)(-2750 3475);
WIRE 17 -1 (-2750 3375)(-2750 3425);
WIRE 17 -1 (-2750 3325)(-2750 3375);
WIRE 17 -1 (-2750 3275)(-2750 3325);
WIRE 17 -1 (-2750 3225)(-2750 3275);
WIRE 17 -1 (-2750 3175)(-2750 3225);
WIRE 17 -1 (-2750 3125)(-2750 3175);
WIRE 17 -1 (-2750 3075)(-2750 3125);
WIRE 17 -1 (-2750 3025)(-2750 3075);
WIRE 17 -1 (-2750 2975)(-2750 3025);
WIRE 17 -1 (-2750 2925)(-2750 2975);
WIRE 17 -1 (-2750 2875)(-2750 2925);
WIRE 17 -1 (-2000 1600)(-2750 1600);
FORCEPROP 2 LAST SIG_NAME M_B_ODT<3:0>
J 0
(-2650 1610);
DISPLAY 0.617021 (-2650 1610);
PAINT ORANGE (-2650 1610);
WIRE 17 -1 (-2750 1575)(-2750 1600);
WIRE 17 -1 (-2750 1525)(-2750 1575);
WIRE 17 -1 (-2750 1475)(-2750 1525);
WIRE 17 -1 (-2750 1425)(-2750 1475);
WIRE 17 -1 (-2000 1350)(-2750 1350);
FORCEPROP 2 LAST SIG_NAME M_B_CS_N<7:0>
J 0
(-2650 1360);
DISPLAY 0.617021 (-2650 1360);
PAINT ORANGE (-2650 1360);
WIRE 17 -1 (-2750 1325)(-2750 1350);
WIRE 17 -1 (-2750 1275)(-2750 1325);
WIRE 17 -1 (-2750 1225)(-2750 1275);
WIRE 17 -1 (-2750 1175)(-2750 1225);
WIRE 17 -1 (-2750 1125)(-2750 1175);
WIRE 17 -1 (-2750 1075)(-2750 1125);
WIRE 17 -1 (-2750 1025)(-2750 1075);
WIRE 17 -1 (-2750 975)(-2750 1025);
WIRE 17 -1 (-2000 1850)(-2750 1850);
FORCEPROP 2 LAST SIG_NAME M_B_CKE<3:0>
J 0
(-2650 1860);
DISPLAY 0.617021 (-2650 1860);
PAINT ORANGE (-2650 1860);
WIRE 17 -1 (-2750 1825)(-2750 1850);
WIRE 17 -1 (-2750 1775)(-2750 1825);
WIRE 17 -1 (-2750 1725)(-2750 1775);
WIRE 17 -1 (-2750 1675)(-2750 1725);
WIRE 17 -1 (-2000 900)(-2750 900);
FORCEPROP 2 LAST SIG_NAME M_B_BG<1:0>
J 0
(-2650 910);
DISPLAY 0.617021 (-2650 910);
PAINT ORANGE (-2650 910);
WIRE 17 -1 (-2750 875)(-2750 900);
WIRE 17 -1 (-2750 825)(-2750 875);
WIRE 17 -1 (-2000 800)(-2750 800);
FORCEPROP 2 LAST SIG_NAME M_B_BA<1:0>
J 0
(-2650 810);
DISPLAY 0.617021 (-2650 810);
PAINT ORANGE (-2650 810);
WIRE 17 -1 (-2750 775)(-2750 800);
WIRE 17 -1 (-2750 725)(-2750 775);
WIRE 17 -1 (-5575 1525)(-5575 1575);
WIRE 17 -1 (-5575 1575)(-5575 1625);
WIRE 17 -1 (-5575 1625)(-5575 1675);
WIRE 17 -1 (-5575 1675)(-5575 1725);
WIRE 17 -1 (-5575 1725)(-5575 1775);
WIRE 17 -1 (-5575 1775)(-5575 1825);
WIRE 17 -1 (-5575 1825)(-5575 1875);
WIRE 17 -1 (-5575 1875)(-5575 1925);
WIRE 17 -1 (-5575 1925)(-5575 1975);
WIRE 17 -1 (-5575 1975)(-5575 2025);
WIRE 17 -1 (-5575 2025)(-5575 2075);
WIRE 17 -1 (-5575 2075)(-5575 2125);
WIRE 17 -1 (-5575 2125)(-5575 2175);
WIRE 17 -1 (-5575 2175)(-5575 2225);
WIRE 17 -1 (-5575 2225)(-5575 2275);
WIRE 17 -1 (-5575 2275)(-5575 2325);
WIRE 17 -1 (-5575 2325)(-5575 2375);
WIRE 17 -1 (-5575 2375)(-5575 2425);
WIRE 17 -1 (-5575 2425)(-5575 2475);
WIRE 17 -1 (-5575 2475)(-5575 2525);
WIRE 17 -1 (-5575 2525)(-5575 2575);
WIRE 17 -1 (-5575 2575)(-5575 2625);
WIRE 17 -1 (-5575 2625)(-5575 2675);
WIRE 17 -1 (-5575 2675)(-5575 2725);
WIRE 17 -1 (-5575 2725)(-5575 2775);
WIRE 17 -1 (-5575 2775)(-5575 2825);
WIRE 17 -1 (-5575 2825)(-5575 2875);
WIRE 17 -1 (-5575 2875)(-5575 2925);
WIRE 17 -1 (-5575 2925)(-5575 2975);
WIRE 17 -1 (-5575 2975)(-5575 3025);
WIRE 17 -1 (-5575 3025)(-5575 3075);
WIRE 17 -1 (-5575 3075)(-5575 3125);
WIRE 17 -1 (-5575 3125)(-5575 3175);
WIRE 17 -1 (-5575 3175)(-5575 3225);
WIRE 17 -1 (-5575 3225)(-5575 3275);
WIRE 17 -1 (-5575 3275)(-5575 3325);
WIRE 17 -1 (-5575 3325)(-5575 3375);
WIRE 17 -1 (-5575 3375)(-5575 3425);
WIRE 17 -1 (-5575 4775)(-6325 4775);
FORCEPROP 2 LAST SIG_NAME M_B_DQ<63:0>
J 0
(-6275 4785);
DISPLAY 0.617021 (-6275 4785);
PAINT ORANGE (-6275 4785);
WIRE 17 -1 (-5575 3425)(-5575 3475);
WIRE 17 -1 (-5575 3475)(-5575 3525);
WIRE 17 -1 (-5575 4675)(-5575 4775);
WIRE 17 -1 (-5575 4625)(-5575 4675);
WIRE 17 -1 (-5575 3525)(-5575 3575);
WIRE 17 -1 (-5575 3575)(-5575 3625);
WIRE 17 -1 (-5575 4575)(-5575 4625);
WIRE 17 -1 (-5575 4525)(-5575 4575);
WIRE 17 -1 (-5575 3625)(-5575 3675);
WIRE 17 -1 (-5575 3675)(-5575 3725);
WIRE 17 -1 (-5575 4475)(-5575 4525);
WIRE 17 -1 (-5575 4425)(-5575 4475);
WIRE 17 -1 (-5575 3725)(-5575 3775);
WIRE 17 -1 (-5575 3775)(-5575 3825);
WIRE 17 -1 (-5575 4375)(-5575 4425);
WIRE 17 -1 (-5575 4325)(-5575 4375);
WIRE 17 -1 (-5575 3825)(-5575 3875);
WIRE 17 -1 (-5575 3875)(-5575 3925);
WIRE 17 -1 (-5575 4275)(-5575 4325);
WIRE 17 -1 (-5575 4225)(-5575 4275);
WIRE 17 -1 (-5575 3925)(-5575 3975);
WIRE 17 -1 (-5575 3975)(-5575 4025);
WIRE 17 -1 (-5575 4175)(-5575 4225);
WIRE 17 -1 (-5575 4125)(-5575 4175);
WIRE 17 -1 (-5575 4025)(-5575 4075);
WIRE 17 -1 (-5575 4075)(-5575 4125);
WIRE 17 -1 (-5575 1450)(-6325 1450);
FORCEPROP 2 LAST SIG_NAME M_B_ECC<7:0>
J 0
(-6275 1460);
DISPLAY 0.617021 (-6275 1460);
PAINT ORANGE (-6275 1460);
WIRE 17 -1 (-5575 1425)(-5575 1450);
WIRE 17 -1 (-5575 1375)(-5575 1425);
WIRE 17 -1 (-5575 1325)(-5575 1375);
WIRE 17 -1 (-5575 1275)(-5575 1325);
WIRE 17 -1 (-5575 1225)(-5575 1275);
WIRE 17 -1 (-5575 1175)(-5575 1225);
WIRE 17 -1 (-5575 1125)(-5575 1175);
WIRE 17 -1 (-5575 1075)(-5575 1125);
WIRE 17 -1 (-5575 1000)(-6325 1000);
FORCEPROP 2 LAST SIG_NAME M_B_CLK_DP<3:0>
J 0
(-6275 1010);
DISPLAY 0.617021 (-6275 1010);
PAINT ORANGE (-6275 1010);
WIRE 17 -1 (-5575 975)(-5575 1000);
WIRE 17 -1 (-5575 925)(-5575 975);
WIRE 17 -1 (-5575 875)(-5575 925);
WIRE 17 -1 (-5575 825)(-5575 875);
WIRE 17 -1 (-5575 800)(-6325 800);
FORCEPROP 2 LAST SIG_NAME M_B_CLK_DN<3:0>
J 0
(-6275 810);
DISPLAY 0.617021 (-6275 810);
PAINT ORANGE (-6275 810);
WIRE 17 -1 (-5575 775)(-5575 800);
WIRE 17 -1 (-5575 725)(-5575 775);
WIRE 17 -1 (-5575 675)(-5575 725);
WIRE 17 -1 (-5575 625)(-5575 675);
WIRE 16 -1 (-3275 3250)(-2850 3250);
WIRE 16 -1 (-4975 4250)(-5475 4250);
WIRE 16 -1 (-5475 3550)(-4975 3550);
WIRE 16 -1 (-3275 3900)(-2850 3900);
WIRE 16 -1 (-5475 2900)(-4975 2900);
WIRE 16 -1 (-4975 4150)(-5475 4150);
WIRE 16 -1 (-3275 1550)(-2850 1550);
WIRE 16 -1 (-5475 3250)(-4975 3250);
WIRE 16 -1 (-5475 3150)(-4975 3150);
WIRE 16 -1 (-5475 3400)(-4975 3400);
WIRE 16 -1 (-5475 2950)(-4975 2950);
WIRE 16 -1 (-5475 1750)(-4975 1750);
WIRE 16 -1 (-4975 500)(-6325 500);
FORCEPROP 2 LAST SIG_NAME M_B_C<2>
J 0
(-6275 510);
DISPLAY 0.617021 (-6275 510);
PAINT ORANGE (-6275 510);
WIRE 16 -1 (-4975 750)(-5475 750);
WIRE 16 -1 (-4975 700)(-5475 700);
WIRE 16 -1 (-4975 650)(-5475 650);
WIRE 16 -1 (-4975 600)(-5475 600);
WIRE 16 -1 (-4975 950)(-5475 950);
WIRE 16 -1 (-4975 900)(-5475 900);
WIRE 16 -1 (-4975 850)(-5475 850);
WIRE 16 -1 (-4975 800)(-5475 800);
WIRE 16 -1 (-5475 2000)(-4975 2000);
WIRE 16 -1 (-5475 1950)(-4975 1950);
WIRE 16 -1 (-5475 1900)(-4975 1900);
WIRE 16 -1 (-5475 1850)(-4975 1850);
WIRE 16 -1 (-5475 1800)(-4975 1800);
WIRE 16 -1 (-5475 1700)(-4975 1700);
WIRE 16 -1 (-5475 1650)(-4975 1650);
WIRE 16 -1 (-5475 1600)(-4975 1600);
WIRE 16 -1 (-5475 1550)(-4975 1550);
WIRE 16 -1 (-5475 1500)(-4975 1500);
WIRE 16 -1 (-4975 1400)(-5475 1400);
WIRE 16 -1 (-5475 1350)(-4975 1350);
WIRE 16 -1 (-5475 1300)(-4975 1300);
WIRE 16 -1 (-4975 1250)(-5475 1250);
WIRE 16 -1 (-5475 1200)(-4975 1200);
WIRE 16 -1 (-5475 1150)(-4975 1150);
WIRE 16 -1 (-5475 1100)(-4975 1100);
WIRE 16 -1 (-5475 1050)(-4975 1050);
WIRE 16 -1 (-5475 4050)(-4975 4050);
WIRE 16 -1 (-4975 4000)(-5475 4000);
WIRE 16 -1 (-5475 3950)(-4975 3950);
WIRE 16 -1 (-5475 3900)(-4975 3900);
WIRE 16 -1 (-4975 3850)(-5475 3850);
WIRE 16 -1 (-5475 3800)(-4975 3800);
WIRE 16 -1 (-5475 3750)(-4975 3750);
WIRE 16 -1 (-4975 3700)(-5475 3700);
WIRE 16 -1 (-5475 3650)(-4975 3650);
WIRE 16 -1 (-5475 3600)(-4975 3600);
WIRE 16 -1 (-5475 3500)(-4975 3500);
WIRE 16 -1 (-5475 3450)(-4975 3450);
WIRE 16 -1 (-5475 3350)(-4975 3350);
WIRE 16 -1 (-5475 3300)(-4975 3300);
WIRE 16 -1 (-5475 3200)(-4975 3200);
WIRE 16 -1 (-5475 3100)(-4975 3100);
WIRE 16 -1 (-5475 3050)(-4975 3050);
WIRE 16 -1 (-5475 3000)(-4975 3000);
WIRE 16 -1 (-5475 2850)(-4975 2850);
WIRE 16 -1 (-5475 2800)(-4975 2800);
WIRE 16 -1 (-5475 2750)(-4975 2750);
WIRE 16 -1 (-5475 2700)(-4975 2700);
WIRE 16 -1 (-5475 2650)(-4975 2650);
WIRE 16 -1 (-5475 2600)(-4975 2600);
WIRE 16 -1 (-5475 2550)(-4975 2550);
WIRE 16 -1 (-5475 2500)(-4975 2500);
WIRE 16 -1 (-5475 2450)(-4975 2450);
WIRE 16 -1 (-5475 2400)(-4975 2400);
WIRE 16 -1 (-5475 2350)(-4975 2350);
WIRE 16 -1 (-5475 2300)(-4975 2300);
WIRE 16 -1 (-5475 2250)(-4975 2250);
WIRE 16 -1 (-5475 2200)(-4975 2200);
WIRE 16 -1 (-5475 2150)(-4975 2150);
WIRE 16 -1 (-5475 2100)(-4975 2100);
WIRE 16 -1 (-5475 2050)(-4975 2050);
WIRE 16 -1 (-4975 4650)(-5475 4650);
WIRE 16 -1 (-4975 4600)(-5475 4600);
WIRE 16 -1 (-4975 4550)(-5475 4550);
WIRE 16 -1 (-4975 4500)(-5475 4500);
WIRE 16 -1 (-4975 4450)(-5475 4450);
WIRE 16 -1 (-4975 4400)(-5475 4400);
WIRE 16 -1 (-4975 4350)(-5475 4350);
WIRE 16 -1 (-4975 4300)(-5475 4300);
WIRE 16 -1 (-4975 4200)(-5475 4200);
WIRE 16 -1 (-5475 4100)(-4975 4100);
WIRE 16 -1 (-3275 750)(-2850 750);
WIRE 16 -1 (-3275 700)(-2850 700);
WIRE 16 -1 (-3275 850)(-2850 850);
WIRE 16 -1 (-3275 800)(-2850 800);
WIRE 16 -1 (-3275 1800)(-2850 1800);
WIRE 16 -1 (-3275 1750)(-2850 1750);
WIRE 16 -1 (-3275 1700)(-2850 1700);
WIRE 16 -1 (-3275 1650)(-2850 1650);
WIRE 16 -1 (-3275 1300)(-2850 1300);
WIRE 16 -1 (-3275 1250)(-2850 1250);
WIRE 16 -1 (-3275 1200)(-2850 1200);
WIRE 16 -1 (-3275 1150)(-2850 1150);
WIRE 16 -1 (-3275 1100)(-2850 1100);
WIRE 16 -1 (-3275 1050)(-2850 1050);
WIRE 16 -1 (-3275 1000)(-2850 1000);
WIRE 16 -1 (-3275 950)(-2850 950);
WIRE 16 -1 (-3275 2000)(-2850 2000);
WIRE 16 -1 (-3275 1950)(-2850 1950);
WIRE 16 -1 (-3275 1900)(-2850 1900);
WIRE 16 -1 (-3275 1500)(-2850 1500);
WIRE 16 -1 (-3275 1450)(-2850 1450);
WIRE 16 -1 (-3275 1400)(-2850 1400);
WIRE 16 -1 (-3275 3700)(-2850 3700);
WIRE 16 -1 (-3275 3650)(-2850 3650);
WIRE 16 -1 (-3275 3600)(-2850 3600);
WIRE 16 -1 (-3275 3550)(-2850 3550);
WIRE 16 -1 (-3275 3500)(-2850 3500);
WIRE 16 -1 (-3275 3450)(-2850 3450);
WIRE 16 -1 (-3275 3400)(-2850 3400);
WIRE 16 -1 (-3275 3350)(-2850 3350);
WIRE 16 -1 (-3275 3300)(-2850 3300);
WIRE 16 -1 (-3275 3200)(-2850 3200);
WIRE 16 -1 (-3275 3150)(-2850 3150);
WIRE 16 -1 (-3275 3100)(-2850 3100);
WIRE 16 -1 (-3275 3050)(-2850 3050);
WIRE 16 -1 (-3275 3000)(-2850 3000);
WIRE 16 -1 (-3275 2950)(-2850 2950);
WIRE 16 -1 (-3275 2900)(-2850 2900);
WIRE 16 -1 (-3275 2850)(-2850 2850);
WIRE 16 -1 (-3275 4050)(-2850 4050);
WIRE 16 -1 (-3275 4000)(-2850 4000);
WIRE 16 -1 (-3275 3950)(-2850 3950);
WIRE 16 -1 (-3275 3850)(-2850 3850);
WIRE 16 -1 (-3275 3800)(-2850 3800);
WIRE 16 -1 (-3275 2750)(-2850 2750);
WIRE 16 -1 (-3275 2700)(-2850 2700);
WIRE 16 -1 (-3275 2650)(-2850 2650);
WIRE 16 -1 (-3275 2600)(-2850 2600);
WIRE 16 -1 (-3275 2550)(-2850 2550);
WIRE 16 -1 (-3275 2500)(-2850 2500);
WIRE 16 -1 (-3275 2450)(-2850 2450);
WIRE 16 -1 (-3275 2400)(-2850 2400);
WIRE 16 -1 (-3275 2350)(-2850 2350);
WIRE 16 -1 (-3275 2300)(-2850 2300);
WIRE 16 -1 (-3275 2250)(-2850 2250);
WIRE 16 -1 (-3275 2200)(-2850 2200);
WIRE 16 -1 (-3275 2150)(-2850 2150);
WIRE 16 -1 (-3275 2100)(-2850 2100);
WIRE 16 -1 (-3275 2050)(-2850 2050);
WIRE 16 -1 (-3275 500)(-2000 500);
FORCEPROP 2 LAST SIG_NAME M_B_PAR
J 0
(-2700 510);
DISPLAY 0.617021 (-2700 510);
PAINT ORANGE (-2700 510);
WIRE 16 -1 (-3275 550)(-2000 550);
FORCEPROP 2 LAST SIG_NAME M_B_ALERT_N
J 0
(-2700 560);
DISPLAY 0.617021 (-2700 560);
PAINT ORANGE (-2700 560);
WIRE 16 -1 (-3275 600)(-2000 600);
FORCEPROP 2 LAST SIG_NAME M_B_ACT_N
J 0
(-2700 610);
DISPLAY 0.617021 (-2700 610);
PAINT ORANGE (-2700 610);
WIRE 16 -1 (-3275 4650)(-2850 4650);
WIRE 16 -1 (-3275 4600)(-2850 4600);
WIRE 16 -1 (-3275 4550)(-2850 4550);
WIRE 16 -1 (-3275 4500)(-2850 4500);
WIRE 16 -1 (-3275 4450)(-2850 4450);
WIRE 16 -1 (-3275 4400)(-2850 4400);
WIRE 16 -1 (-3275 4350)(-2850 4350);
WIRE 16 -1 (-3275 4300)(-2850 4300);
WIRE 16 -1 (-3275 4250)(-2850 4250);
WIRE 16 -1 (-3275 4200)(-2850 4200);
WIRE 16 -1 (-3275 4150)(-2850 4150);
WIRE 16 -1 (-3275 4100)(-2850 4100);
FORCENOTE
SKYLAKE - SKT0 - 4 OF 21
(-1650 150) 0;
DISPLAY LEFT (-1650 150);
DISPLAY 1.021277 (-1650 150);
PAINT RED (-1650 150);
FORCENOTE
ROOM=CPU0
(-7925 350) 0;
DISPLAY LEFT (-7925 350);
DISPLAY 1.382979 (-7925 350);
PAINT PURPLE (-7925 350);
FORCENOTE
BOM_COST=PROC_SOCKET
(-7925 225) 0;
DISPLAY LEFT (-7925 225);
DISPLAY 1.382979 (-7925 225);
PAINT PURPLE (-7925 225);
QUIT
